FILE_TYPE = MACRO_DRAWING;
SET COLOR_WIRE YELLOW;
SET COLOR_PROP MONO;
SET COLOR_DOT WHITE;
SET COLOR_ARC YELLOW;
SET COLOR_BODY GREEN;
SET COLOR_NOTE MONO;
SET PROP_DISPLAY VALUE;
SET PAGE_NUMBER P133;
FORCEADD GND..1
(-2825 3600);
FORCEPROP 3 LASTPIN (-2825 3650) SIG_NAME GND\g
J 0
(-2815 3660);
DISPLAY 0.659574 (-2815 3660);
PAINT MONO (-2815 3660);
DISPLAY INVISIBLE (-2815 3660);
FORCEPROP 1 LAST BODY_TYPE PLUMBING
J 0
(-2870 3557);
DISPLAY 0.340426 (-2870 3557);
PAINT GREEN (-2870 3557);
DISPLAY INVISIBLE (-2870 3557);
FORCEPROP 1 LAST SIZE 1B
J 0
(-2750 3550);
DISPLAY 1.468085 (-2750 3550);
PAINT GREEN (-2750 3550);
DISPLAY INVISIBLE (-2750 3550);
FORCEPROP 2 LAST CDS_LIB mstr_symbols
J 0
(-2825 3600);
PAINT MONO (-2825 3600);
DISPLAY INVISIBLE (-2825 3600);
FORCEPROP 2 LAST BOM_COST SB
J 0
(-2875 3675);
PAINT MONO (-2875 3675);
DISPLAY INVISIBLE (-2875 3675);
FORCEPROP 1 LAST HDL_POWER GND
J 0
(-2825 3750);
DISPLAY 1.468085 (-2825 3750);
PAINT GREEN (-2825 3750);
DISPLAY INVISIBLE (-2825 3750);
FORCEPROP 1 LAST VOLTAGE 0
J 0
(-2825 3600);
PAINT SKYBLUE (-2825 3600);
DISPLAY INVISIBLE (-2825 3600);
FORCEPROP 1 LAST PATH I110
J 0
(-2750 3600);
DISPLAY 1.170213 (-2750 3600);
PAINT GREEN (-2750 3600);
DISPLAY INVISIBLE (-2750 3600);
FORCEADD OFFPAGE..2
(-1600 4075);
FORCEPROP 2 LAST $XR0 191 
J 0
(-1411 4075);
DISPLAY 0.638298 (-1411 4075);
PAINT MONO (-1411 4075);
FORCEPROP 2 LAST $XR1 118 
J 0
(-1291 4075);
DISPLAY 0.638298 (-1291 4075);
PAINT MONO (-1291 4075);
FORCEPROP 2 LAST $XR2 144 
J 0
(-1171 4075);
DISPLAY 0.638298 (-1171 4075);
PAINT MONO (-1171 4075);
FORCEPROP 1 LAST COMMENT_BODY TRUE
J 0
(-1645 3980);
DISPLAY 1.170213 (-1645 3980);
PAINT GREEN (-1645 3980);
DISPLAY INVISIBLE (-1645 3980);
FORCEPROP 1 LAST OFFPAGE TRUE
J 0
(-1275 3950);
PAINT GREEN (-1275 3950);
DISPLAY INVISIBLE (-1275 3950);
FORCEPROP 2 LAST CDS_LIB mstr_standard
J 0
(-1600 4075);
PAINT MONO (-1600 4075);
DISPLAY INVISIBLE (-1600 4075);
FORCEPROP 2 LAST PATH I112
J 0
(-1425 4150);
PAINT MONO (-1425 4150);
DISPLAY INVISIBLE (-1425 4150);
FORCEPROP 2 LAST BOM_COST SB
J 0
(-1150 4125);
PAINT MONO (-1150 4125);
DISPLAY INVISIBLE (-1150 4125);
FORCEADD OFFPAGE..2
(-1600 3850);
FORCEPROP 2 LAST $XR0 191 
J 0
(-1411 3850);
DISPLAY 0.638298 (-1411 3850);
PAINT MONO (-1411 3850);
FORCEPROP 2 LAST $XR1 118 
J 0
(-1291 3850);
DISPLAY 0.638298 (-1291 3850);
PAINT MONO (-1291 3850);
FORCEPROP 2 LAST $XR2 144 
J 0
(-1171 3850);
DISPLAY 0.638298 (-1171 3850);
PAINT MONO (-1171 3850);
FORCEPROP 1 LAST COMMENT_BODY TRUE
J 0
(-1645 3755);
DISPLAY 1.170213 (-1645 3755);
PAINT GREEN (-1645 3755);
DISPLAY INVISIBLE (-1645 3755);
FORCEPROP 2 LAST CDS_LIB mstr_standard
J 0
(-1600 3850);
PAINT MONO (-1600 3850);
DISPLAY INVISIBLE (-1600 3850);
FORCEPROP 2 LAST PATH I117
J 0
(-1425 3925);
PAINT MONO (-1425 3925);
DISPLAY INVISIBLE (-1425 3925);
FORCEPROP 1 LAST OFFPAGE TRUE
J 0
(-1275 3725);
PAINT GREEN (-1275 3725);
DISPLAY INVISIBLE (-1275 3725);
FORCEPROP 2 LAST BOM_COST SB
J 0
(-1050 3900);
PAINT MONO (-1050 3900);
DISPLAY INVISIBLE (-1050 3900);
FORCEADD RES..1
(-2500 3850);
FORCEPROP 1 LAST WATTAGE 1/16W
J 2
(-2570 3760);
DISPLAY 0.617021 (-2570 3760);
PAINT SKYBLUE (-2570 3760);
FORCEPROP 1 LAST LOCATION R3N3
J 0
(-2750 3875);
DISPLAY 0.617021 (-2750 3875);
PAINT AQUA (-2750 3875);
FORCEPROP 1 LAST VALUE 2.0K
J 2
(-2525 3800);
DISPLAY 0.617021 (-2525 3800);
PAINT SKYBLUE (-2525 3800);
FORCEPROP 1 LAST MATERIAL CHIP
J 0
(-2560 3760);
DISPLAY 0.617021 (-2560 3760);
PAINT SKYBLUE (-2560 3760);
FORCEPROP 1 LASTPIN (-2600 3850) $PN 1
J 0
(-2588 3862);
DISPLAY 0.617021 (-2588 3862);
PAINT MONO (-2588 3862);
FORCEPROP 1 LAST TOLERANCE 1%
J 0
(-2470 3800);
DISPLAY 0.617021 (-2470 3800);
PAINT SKYBLUE (-2470 3800);
FORCEPROP 1 LASTPIN (-2400 3850) $PN 2
J 0
(-2438 3862);
DISPLAY 0.617021 (-2438 3862);
PAINT MONO (-2438 3862);
FORCEPROP 1 LAST PART_NUMBER G21796-001
J 0
(-2425 3900);
DISPLAY 0.617021 (-2425 3900);
PAINT BLUE (-2425 3900);
FORCEPROP 1 LAST PACK_TYPE 0402
J 0
(-2390 3810);
DISPLAY 0.617021 (-2390 3810);
PAINT SKYBLUE (-2390 3810);
FORCEPROP 2 LAST CDS_LOCATION R3N3
J 0
(-2750 3875);
DISPLAY 0.617021 (-2750 3875);
PAINT AQUA (-2750 3875);
DISPLAY INVISIBLE (-2750 3875);
FORCEPROP 2 LAST BOM_COST SB
J 0
(-2550 3700);
PAINT MONO (-2550 3700);
DISPLAY INVISIBLE (-2550 3700);
FORCEPROP 2 LAST ROOM SB
J 0
(-2500 3850);
PAINT MONO (-2500 3850);
DISPLAY INVISIBLE (-2500 3850);
FORCEPROP 2 LAST CDS_LIB mstr_discrete
J 0
(-2500 3850);
PAINT MONO (-2500 3850);
DISPLAY INVISIBLE (-2500 3850);
FORCEPROP 2 LAST $SEC 1
J 0
(-2550 4050);
DISPLAY 0.936170 (-2550 4050);
PAINT MONO (-2550 4050);
DISPLAY INVISIBLE (-2550 4050);
FORCEPROP 1 LAST PATH I120
J 0
(-2550 4000);
DISPLAY 1.319149 (-2550 4000);
PAINT GREEN (-2550 4000);
DISPLAY INVISIBLE (-2550 4000);
FORCEPROP 2 LAST CDS_SEC 1
J 0
(-2550 4050);
DISPLAY 1.404255 (-2550 4050);
PAINT ORANGE (-2550 4050);
DISPLAY INVISIBLE (-2550 4050);
FORCEADD RES..1
(-2500 4075);
FORCEPROP 1 LAST WATTAGE 1/16W
J 2
(-2570 3985);
DISPLAY 0.617021 (-2570 3985);
PAINT SKYBLUE (-2570 3985);
FORCEPROP 1 LAST MATERIAL EMPTY
J 0
(-2560 3985);
DISPLAY 0.617021 (-2560 3985);
PAINT RED (-2560 3985);
FORCEPROP 1 LAST VALUE 10.0K
J 2
(-2525 4025);
DISPLAY 0.617021 (-2525 4025);
PAINT SKYBLUE (-2525 4025);
FORCEPROP 1 LAST TOLERANCE 1%
J 0
(-2470 4025);
DISPLAY 0.617021 (-2470 4025);
PAINT SKYBLUE (-2470 4025);
FORCEPROP 1 LAST PACK_TYPE 0402
J 0
(-2390 4035);
DISPLAY 0.617021 (-2390 4035);
PAINT SKYBLUE (-2390 4035);
FORCEPROP 1 LASTPIN (-2400 4075) $PN 2
J 0
(-2438 4087);
DISPLAY 0.617021 (-2438 4087);
PAINT MONO (-2438 4087);
FORCEPROP 1 LASTPIN (-2600 4075) $PN 1
J 0
(-2588 4087);
DISPLAY 0.617021 (-2588 4087);
PAINT MONO (-2588 4087);
FORCEPROP 1 LAST LOCATION R2N12
J 0
(-2750 4100);
DISPLAY 0.617021 (-2750 4100);
PAINT AQUA (-2750 4100);
FORCEPROP 1 LAST PART_NUMBER G21796-016
J 0
(-2425 4125);
DISPLAY 0.617021 (-2425 4125);
PAINT BLUE (-2425 4125);
FORCEPROP 2 LAST BOM_COST SB
J 0
(-2550 3925);
PAINT MONO (-2550 3925);
DISPLAY INVISIBLE (-2550 3925);
FORCEPROP 2 LAST ROOM SB
J 0
(-2500 4075);
PAINT MONO (-2500 4075);
DISPLAY INVISIBLE (-2500 4075);
FORCEPROP 2 LAST CDS_LIB mstr_discrete
J 0
(-2500 4075);
PAINT MONO (-2500 4075);
DISPLAY INVISIBLE (-2500 4075);
FORCEPROP 2 LAST CDS_LOCATION R2N12
J 0
(-2750 4100);
DISPLAY 0.617021 (-2750 4100);
PAINT AQUA (-2750 4100);
DISPLAY INVISIBLE (-2750 4100);
FORCEPROP 2 LAST CDS_SEC 1
J 0
(-2550 4275);
DISPLAY 1.404255 (-2550 4275);
PAINT ORANGE (-2550 4275);
DISPLAY INVISIBLE (-2550 4275);
FORCEPROP 2 LAST $SEC 1
J 0
(-2550 4275);
DISPLAY 0.936170 (-2550 4275);
PAINT MONO (-2550 4275);
DISPLAY INVISIBLE (-2550 4275);
FORCEPROP 1 LAST PATH I122
J 0
(-2550 4225);
DISPLAY 1.319149 (-2550 4225);
PAINT GREEN (-2550 4225);
DISPLAY INVISIBLE (-2550 4225);
FORCEADD RES..1
(-4700 4500);
FORCEPROP 1 LAST VALUE 10.0K
J 2
(-4725 4400);
DISPLAY 0.617021 (-4725 4400);
PAINT SKYBLUE (-4725 4400);
FORCEPROP 1 LASTPIN (-4800 4500) $PN 1
J 0
(-4788 4512);
DISPLAY 0.617021 (-4788 4512);
PAINT ORANGE (-4788 4512);
FORCEPROP 1 LAST LOCATION R7D8
J 0
(-4750 4550);
DISPLAY 0.617021 (-4750 4550);
PAINT AQUA (-4750 4550);
FORCEPROP 1 LAST TOLERANCE 1%
J 0
(-4700 4400);
DISPLAY 0.617021 (-4700 4400);
PAINT SKYBLUE (-4700 4400);
FORCEPROP 1 LASTPIN (-4600 4500) $PN 2
J 0
(-4638 4512);
DISPLAY 0.617021 (-4638 4512);
PAINT ORANGE (-4638 4512);
FORCEPROP 1 LAST WATTAGE 1/16W
J 2
(-4475 4400);
DISPLAY 0.617021 (-4475 4400);
PAINT SKYBLUE (-4475 4400);
FORCEPROP 1 LAST MATERIAL CHIP
J 0
(-4450 4400);
DISPLAY 0.617021 (-4450 4400);
PAINT SKYBLUE (-4450 4400);
FORCEPROP 1 LAST PACK_TYPE 0402
J 0
(-4325 4400);
DISPLAY 0.617021 (-4325 4400);
PAINT SKYBLUE (-4325 4400);
FORCEPROP 1 LAST PART_NUMBER G21796-016
J 0
(-4200 4400);
DISPLAY 0.617021 (-4200 4400);
PAINT BLUE (-4200 4400);
FORCEPROP 2 LAST CDS_LOCATION R7D8
J 0
(-4750 4550);
DISPLAY 0.617021 (-4750 4550);
PAINT AQUA (-4750 4550);
DISPLAY INVISIBLE (-4750 4550);
FORCEPROP 2 LAST CDS_LIB mstr_discrete
J 0
(-4700 4500);
PAINT ORANGE (-4700 4500);
DISPLAY INVISIBLE (-4700 4500);
FORCEPROP 0 LAST ROOM SB
J 0
(-4750 4650);
DISPLAY 1.021277 (-4750 4650);
PAINT ORANGE (-4750 4650);
DISPLAY INVISIBLE (-4750 4650);
FORCEPROP 2 LAST SEC_TYPE 0402
J 0
(-4750 4700);
DISPLAY 1.021277 (-4750 4700);
PAINT ORANGE (-4750 4700);
DISPLAY INVISIBLE (-4750 4700);
FORCEPROP 2 LAST SEC 1
J 0
(-4750 4700);
DISPLAY 0.680851 (-4750 4700);
PAINT MONO (-4750 4700);
DISPLAY INVISIBLE (-4750 4700);
FORCEPROP 1 LAST PATH I200
J 0
(-4750 4650);
DISPLAY 0.978723 (-4750 4650);
PAINT WHITE (-4750 4650);
DISPLAY INVISIBLE (-4750 4650);
FORCEADD RES..1
(-4700 4325);
FORCEPROP 1 LAST VALUE 10.0K
J 2
(-4725 4225);
DISPLAY 0.617021 (-4725 4225);
PAINT SKYBLUE (-4725 4225);
FORCEPROP 1 LAST TOLERANCE 1%
J 0
(-4700 4225);
DISPLAY 0.617021 (-4700 4225);
PAINT SKYBLUE (-4700 4225);
FORCEPROP 1 LASTPIN (-4600 4325) $PN 2
J 0
(-4638 4337);
DISPLAY 0.617021 (-4638 4337);
PAINT ORANGE (-4638 4337);
FORCEPROP 1 LASTPIN (-4800 4325) $PN 1
J 0
(-4788 4337);
DISPLAY 0.617021 (-4788 4337);
PAINT ORANGE (-4788 4337);
FORCEPROP 1 LAST WATTAGE 1/16W
J 2
(-4475 4225);
DISPLAY 0.617021 (-4475 4225);
PAINT SKYBLUE (-4475 4225);
FORCEPROP 1 LAST LOCATION R7D10
J 0
(-4750 4375);
DISPLAY 0.617021 (-4750 4375);
PAINT AQUA (-4750 4375);
FORCEPROP 1 LAST MATERIAL CHIP
J 0
(-4450 4225);
DISPLAY 0.617021 (-4450 4225);
PAINT SKYBLUE (-4450 4225);
FORCEPROP 1 LAST PACK_TYPE 0402
J 0
(-4325 4225);
DISPLAY 0.617021 (-4325 4225);
PAINT SKYBLUE (-4325 4225);
FORCEPROP 1 LAST PART_NUMBER G21796-016
J 0
(-4200 4225);
DISPLAY 0.617021 (-4200 4225);
PAINT BLUE (-4200 4225);
FORCEPROP 2 LAST CDS_LIB mstr_discrete
J 0
(-4700 4325);
PAINT ORANGE (-4700 4325);
DISPLAY INVISIBLE (-4700 4325);
FORCEPROP 1 LAST PATH I202
J 0
(-4750 4475);
DISPLAY 0.978723 (-4750 4475);
PAINT WHITE (-4750 4475);
DISPLAY INVISIBLE (-4750 4475);
FORCEPROP 2 LAST CDS_LOCATION R7D10
J 0
(-4750 4375);
DISPLAY 0.617021 (-4750 4375);
PAINT AQUA (-4750 4375);
DISPLAY INVISIBLE (-4750 4375);
FORCEPROP 2 LAST SEC 1
J 0
(-4750 4525);
DISPLAY 0.680851 (-4750 4525);
PAINT MONO (-4750 4525);
DISPLAY INVISIBLE (-4750 4525);
FORCEPROP 2 LAST SEC_TYPE 0402
J 0
(-4750 4525);
DISPLAY 1.021277 (-4750 4525);
PAINT ORANGE (-4750 4525);
DISPLAY INVISIBLE (-4750 4525);
FORCEPROP 0 LAST ROOM SB
J 0
(-4750 4475);
DISPLAY 1.021277 (-4750 4475);
PAINT ORANGE (-4750 4475);
DISPLAY INVISIBLE (-4750 4475);
FORCEADD OFFPAGE..2
(-3850 5100);
FORCEPROP 2 LAST $XR0 119 
J 0
(-3661 5100);
DISPLAY 0.638298 (-3661 5100);
PAINT MONO (-3661 5100);
FORCEPROP 2 LASTPIN (-3900 5100) SIG_NAME PU_FM_RCIN_N
J 0
(-4435 5110);
DISPLAY 0.617021 (-4435 5110);
PAINT ORANGE (-4435 5110);
FORCEPROP 1 LAST COMMENT_BODY TRUE
J 0
(-3895 5005);
DISPLAY 0.872340 (-3895 5005);
PAINT GREEN (-3895 5005);
DISPLAY INVISIBLE (-3895 5005);
FORCEPROP 1 LAST OFFPAGE TRUE
J 0
(-3525 4975);
DISPLAY 0.872340 (-3525 4975);
PAINT GREEN (-3525 4975);
DISPLAY INVISIBLE (-3525 4975);
FORCEPROP 2 LAST CDS_LIB mstr_standard
J 0
(-3850 5100);
PAINT ORANGE (-3850 5100);
DISPLAY INVISIBLE (-3850 5100);
FORCEPROP 2 LAST PATH I204
J 0
(-3675 5175);
DISPLAY 1.021277 (-3675 5175);
PAINT ORANGE (-3675 5175);
DISPLAY INVISIBLE (-3675 5175);
FORCEADD OFFPAGE..2
(-3850 4700);
FORCEPROP 2 LAST $XR0 184 
J 0
(-3661 4700);
DISPLAY 0.638298 (-3661 4700);
PAINT MONO (-3661 4700);
FORCEPROP 2 LAST $XR1 119 
J 0
(-3541 4700);
DISPLAY 0.638298 (-3541 4700);
PAINT MONO (-3541 4700);
FORCEPROP 1 LAST COMMENT_BODY TRUE
J 0
(-3895 4605);
DISPLAY 0.872340 (-3895 4605);
PAINT GREEN (-3895 4605);
DISPLAY INVISIBLE (-3895 4605);
FORCEPROP 2 LAST CDS_LIB mstr_standard
J 0
(-3850 4700);
PAINT ORANGE (-3850 4700);
DISPLAY INVISIBLE (-3850 4700);
FORCEPROP 2 LAST PATH I205
J 0
(-3675 4775);
DISPLAY 1.021277 (-3675 4775);
PAINT ORANGE (-3675 4775);
DISPLAY INVISIBLE (-3675 4775);
FORCEPROP 1 LAST OFFPAGE TRUE
J 0
(-3525 4575);
DISPLAY 0.872340 (-3525 4575);
PAINT GREEN (-3525 4575);
DISPLAY INVISIBLE (-3525 4575);
FORCEADD OFFPAGE..2
(-3850 4500);
FORCEPROP 2 LAST $XR0 119 
J 0
(-3661 4500);
DISPLAY 0.638298 (-3661 4500);
PAINT MONO (-3661 4500);
FORCEPROP 1 LAST COMMENT_BODY TRUE
J 0
(-3895 4405);
DISPLAY 0.872340 (-3895 4405);
PAINT GREEN (-3895 4405);
DISPLAY INVISIBLE (-3895 4405);
FORCEPROP 2 LAST CDS_LIB mstr_standard
J 0
(-3850 4500);
PAINT ORANGE (-3850 4500);
DISPLAY INVISIBLE (-3850 4500);
FORCEPROP 2 LAST PATH I206
J 0
(-3675 4575);
DISPLAY 1.021277 (-3675 4575);
PAINT ORANGE (-3675 4575);
DISPLAY INVISIBLE (-3675 4575);
FORCEPROP 1 LAST OFFPAGE TRUE
J 0
(-3525 4375);
DISPLAY 0.872340 (-3525 4375);
PAINT GREEN (-3525 4375);
DISPLAY INVISIBLE (-3525 4375);
FORCEADD OFFPAGE..2
(-3850 4325);
FORCEPROP 2 LAST $XR0 119 
J 0
(-3661 4325);
DISPLAY 0.638298 (-3661 4325);
PAINT MONO (-3661 4325);
FORCEPROP 1 LAST COMMENT_BODY TRUE
J 0
(-3895 4230);
DISPLAY 0.872340 (-3895 4230);
PAINT GREEN (-3895 4230);
DISPLAY INVISIBLE (-3895 4230);
FORCEPROP 2 LAST CDS_LIB mstr_standard
J 0
(-3850 4325);
PAINT ORANGE (-3850 4325);
DISPLAY INVISIBLE (-3850 4325);
FORCEPROP 2 LAST PATH I208
J 0
(-3675 4400);
DISPLAY 1.021277 (-3675 4400);
PAINT ORANGE (-3675 4400);
DISPLAY INVISIBLE (-3675 4400);
FORCEPROP 1 LAST OFFPAGE TRUE
J 0
(-3525 4200);
DISPLAY 0.872340 (-3525 4200);
PAINT GREEN (-3525 4200);
DISPLAY INVISIBLE (-3525 4200);
FORCEADD RES..1
(-4700 3925);
FORCEPROP 1 LAST VALUE 10.0K
J 2
(-4725 3825);
DISPLAY 0.617021 (-4725 3825);
PAINT SKYBLUE (-4725 3825);
FORCEPROP 1 LAST TOLERANCE 1%
J 0
(-4700 3825);
DISPLAY 0.617021 (-4700 3825);
PAINT SKYBLUE (-4700 3825);
FORCEPROP 1 LASTPIN (-4800 3925) $PN 1
J 0
(-4788 3937);
DISPLAY 0.617021 (-4788 3937);
PAINT ORANGE (-4788 3937);
FORCEPROP 1 LASTPIN (-4600 3925) $PN 2
J 0
(-4638 3937);
DISPLAY 0.617021 (-4638 3937);
PAINT ORANGE (-4638 3937);
FORCEPROP 1 LAST WATTAGE 1/16W
J 2
(-4475 3825);
DISPLAY 0.617021 (-4475 3825);
PAINT SKYBLUE (-4475 3825);
FORCEPROP 1 LAST LOCATION R7D12
J 0
(-4750 3975);
DISPLAY 0.617021 (-4750 3975);
PAINT AQUA (-4750 3975);
FORCEPROP 1 LAST PACK_TYPE 0402
J 0
(-4325 3825);
DISPLAY 0.617021 (-4325 3825);
PAINT SKYBLUE (-4325 3825);
FORCEPROP 1 LAST MATERIAL CHIP
J 0
(-4450 3825);
DISPLAY 0.617021 (-4450 3825);
PAINT SKYBLUE (-4450 3825);
FORCEPROP 1 LAST PART_NUMBER G21796-016
J 0
(-4200 3825);
DISPLAY 0.617021 (-4200 3825);
PAINT BLUE (-4200 3825);
FORCEPROP 2 LAST CDS_LOCATION R7D12
J 0
(-4750 3975);
DISPLAY 0.617021 (-4750 3975);
PAINT AQUA (-4750 3975);
DISPLAY INVISIBLE (-4750 3975);
FORCEPROP 2 LAST CDS_LIB mstr_discrete
J 0
(-4700 3925);
PAINT MONO (-4700 3925);
DISPLAY INVISIBLE (-4700 3925);
FORCEPROP 0 LAST ROOM SB
J 0
(-4750 4075);
DISPLAY 1.021277 (-4750 4075);
PAINT ORANGE (-4750 4075);
DISPLAY INVISIBLE (-4750 4075);
FORCEPROP 1 LAST PATH I237
J 0
(-4750 4075);
DISPLAY 0.978723 (-4750 4075);
PAINT WHITE (-4750 4075);
DISPLAY INVISIBLE (-4750 4075);
FORCEPROP 2 LAST SEC_TYPE 0402
J 0
(-4750 4125);
DISPLAY 1.021277 (-4750 4125);
PAINT ORANGE (-4750 4125);
DISPLAY INVISIBLE (-4750 4125);
FORCEPROP 2 LAST SEC 1
J 0
(-4750 4125);
DISPLAY 0.680851 (-4750 4125);
PAINT MONO (-4750 4125);
DISPLAY INVISIBLE (-4750 4125);
FORCEADD OFFPAGE..2
(-3850 3925);
FORCEPROP 2 LAST $XR2 119 
J 0
(-3541 3925);
DISPLAY 0.638298 (-3541 3925);
PAINT MONO (-3541 3925);
FORCEPROP 2 LAST $XR0 145 
J 0
(-3661 3925);
DISPLAY 0.638298 (-3661 3925);
PAINT MONO (-3661 3925);
FORCEPROP 2 LAST $XR1 186 
J 0
(-3541 3925);
DISPLAY 0.638298 (-3541 3925);
PAINT MONO (-3541 3925);
FORCEPROP 1 LAST COMMENT_BODY TRUE
J 0
(-3895 3830);
DISPLAY 0.872340 (-3895 3830);
PAINT GREEN (-3895 3830);
DISPLAY INVISIBLE (-3895 3830);
FORCEPROP 2 LAST CDS_LIB mstr_standard
J 0
(-3850 3925);
PAINT MONO (-3850 3925);
DISPLAY INVISIBLE (-3850 3925);
FORCEPROP 2 LAST PATH I238
J 0
(-3675 4000);
DISPLAY 1.021277 (-3675 4000);
PAINT ORANGE (-3675 4000);
DISPLAY INVISIBLE (-3675 4000);
FORCEPROP 1 LAST OFFPAGE TRUE
J 0
(-3525 3800);
DISPLAY 0.872340 (-3525 3800);
PAINT GREEN (-3525 3800);
DISPLAY INVISIBLE (-3525 3800);
FORCEADD OFFPAGE..2
(-3850 3700);
FORCEPROP 2 LAST $XR0 120 
J 0
(-3661 3700);
DISPLAY 0.638298 (-3661 3700);
PAINT MONO (-3661 3700);
FORCEPROP 2 LAST $XR1 146 
J 0
(-3541 3700);
DISPLAY 0.638298 (-3541 3700);
PAINT MONO (-3541 3700);
FORCEPROP 2 LAST $XR2 119 
J 0
(-3421 3700);
DISPLAY 0.638298 (-3421 3700);
PAINT MONO (-3421 3700);
FORCEPROP 2 LAST $XR3 182 
J 0
(-3301 3700);
DISPLAY 0.638298 (-3301 3700);
PAINT MONO (-3301 3700);
FORCEPROP 2 LAST CDS_LIB mstr_standard
J 0
(-3850 3700);
PAINT MONO (-3850 3700);
DISPLAY INVISIBLE (-3850 3700);
FORCEPROP 1 LAST COMMENT_BODY TRUE
J 0
(-3895 3605);
DISPLAY 0.872340 (-3895 3605);
PAINT GREEN (-3895 3605);
DISPLAY INVISIBLE (-3895 3605);
FORCEPROP 2 LAST PATH I242
J 0
(-3675 3775);
DISPLAY 1.021277 (-3675 3775);
PAINT ORANGE (-3675 3775);
DISPLAY INVISIBLE (-3675 3775);
FORCEPROP 1 LAST OFFPAGE TRUE
J 0
(-3525 3575);
DISPLAY 0.872340 (-3525 3575);
PAINT GREEN (-3525 3575);
DISPLAY INVISIBLE (-3525 3575);
FORCEADD RES..1
(-4700 4900);
FORCEPROP 1 LAST WATTAGE 1/16W
J 2
(-4725 4750);
DISPLAY 0.617021 (-4725 4750);
PAINT SKYBLUE (-4725 4750);
FORCEPROP 1 LAST VALUE 4.75K
J 2
(-4725 4800);
DISPLAY 0.617021 (-4725 4800);
PAINT SKYBLUE (-4725 4800);
FORCEPROP 1 LAST TOLERANCE 1%
J 0
(-4700 4800);
DISPLAY 0.617021 (-4700 4800);
PAINT SKYBLUE (-4700 4800);
FORCEPROP 1 LASTPIN (-4800 4900) $PN 1
J 0
(-4788 4912);
DISPLAY 0.617021 (-4788 4912);
PAINT ORANGE (-4788 4912);
FORCEPROP 1 LAST LOCATION R7D3
J 0
(-4750 4950);
DISPLAY 0.617021 (-4750 4950);
PAINT AQUA (-4750 4950);
FORCEPROP 1 LASTPIN (-4600 4900) $PN 2
J 0
(-4638 4912);
DISPLAY 0.617021 (-4638 4912);
PAINT ORANGE (-4638 4912);
FORCEPROP 1 LAST PART_NUMBER G21796-072
J 0
(-4750 5000);
DISPLAY 0.617021 (-4750 5000);
PAINT BLUE (-4750 5000);
FORCEPROP 1 LAST MATERIAL CHIP
J 0
(-4700 4750);
DISPLAY 0.617021 (-4700 4750);
PAINT SKYBLUE (-4700 4750);
FORCEPROP 1 LAST PACK_TYPE 0402
J 0
(-4450 4750);
DISPLAY 0.617021 (-4450 4750);
PAINT SKYBLUE (-4450 4750);
FORCEPROP 0 LAST ROOM SB
J 0
(-4750 5050);
DISPLAY 1.021277 (-4750 5050);
PAINT ORANGE (-4750 5050);
DISPLAY INVISIBLE (-4750 5050);
FORCEPROP 2 LAST CDS_LOCATION R7D3
J 0
(-4750 4950);
DISPLAY 0.617021 (-4750 4950);
PAINT AQUA (-4750 4950);
DISPLAY INVISIBLE (-4750 4950);
FORCEPROP 1 LAST PATH I243
J 0
(-4750 5050);
DISPLAY 0.978723 (-4750 5050);
PAINT WHITE (-4750 5050);
DISPLAY INVISIBLE (-4750 5050);
FORCEPROP 2 LAST CDS_LIB mstr_discrete
J 0
(-4700 4900);
PAINT ORANGE (-4700 4900);
DISPLAY INVISIBLE (-4700 4900);
FORCEPROP 2 LAST SEC_TYPE 0402
J 0
(-4750 5100);
DISPLAY 1.021277 (-4750 5100);
PAINT ORANGE (-4750 5100);
DISPLAY INVISIBLE (-4750 5100);
FORCEPROP 2 LAST SEC 1
J 0
(-4750 5100);
DISPLAY 0.680851 (-4750 5100);
PAINT MONO (-4750 5100);
DISPLAY INVISIBLE (-4750 5100);
FORCEADD OFFPAGE..2
(-3850 4900);
FORCEPROP 2 LAST $XR0 146 
J 0
(-3661 4900);
DISPLAY 0.638298 (-3661 4900);
PAINT MONO (-3661 4900);
FORCEPROP 2 LAST $XR1 119 
J 0
(-3541 4900);
DISPLAY 0.638298 (-3541 4900);
PAINT MONO (-3541 4900);
FORCEPROP 1 LAST COMMENT_BODY TRUE
J 0
(-3895 4805);
DISPLAY 0.872340 (-3895 4805);
PAINT GREEN (-3895 4805);
DISPLAY INVISIBLE (-3895 4805);
FORCEPROP 2 LAST CDS_LIB mstr_standard
J 0
(-3850 4900);
PAINT ORANGE (-3850 4900);
DISPLAY INVISIBLE (-3850 4900);
FORCEPROP 2 LAST PATH I244
J 0
(-3525 4950);
DISPLAY 1.021277 (-3525 4950);
PAINT ORANGE (-3525 4950);
DISPLAY INVISIBLE (-3525 4950);
FORCEPROP 1 LAST OFFPAGE TRUE
J 0
(-3525 4775);
DISPLAY 0.872340 (-3525 4775);
PAINT GREEN (-3525 4775);
DISPLAY INVISIBLE (-3525 4775);
FORCEADD RES..1
(-4700 4125);
FORCEPROP 1 LAST VALUE 10.0K
J 2
(-4725 4025);
DISPLAY 0.617021 (-4725 4025);
PAINT SKYBLUE (-4725 4025);
FORCEPROP 1 LAST TOLERANCE 1%
J 0
(-4700 4025);
DISPLAY 0.617021 (-4700 4025);
PAINT SKYBLUE (-4700 4025);
FORCEPROP 1 LAST WATTAGE 1/16W
J 2
(-4475 4025);
DISPLAY 0.617021 (-4475 4025);
PAINT SKYBLUE (-4475 4025);
FORCEPROP 1 LAST PACK_TYPE 0402
J 0
(-4325 4025);
DISPLAY 0.617021 (-4325 4025);
PAINT SKYBLUE (-4325 4025);
FORCEPROP 1 LAST MATERIAL CHIP
J 0
(-4450 4025);
DISPLAY 0.617021 (-4450 4025);
PAINT SKYBLUE (-4450 4025);
FORCEPROP 1 LASTPIN (-4800 4125) $PN 1
J 0
(-4788 4137);
DISPLAY 0.617021 (-4788 4137);
PAINT ORANGE (-4788 4137);
FORCEPROP 1 LAST LOCATION R7D4
J 0
(-4750 4175);
DISPLAY 0.617021 (-4750 4175);
PAINT AQUA (-4750 4175);
FORCEPROP 1 LASTPIN (-4600 4125) $PN 2
J 0
(-4638 4137);
DISPLAY 0.617021 (-4638 4137);
PAINT ORANGE (-4638 4137);
FORCEPROP 1 LAST PART_NUMBER G21796-016
J 0
(-4200 4025);
DISPLAY 0.617021 (-4200 4025);
PAINT BLUE (-4200 4025);
FORCEPROP 0 LAST ROOM SB
J 0
(-4750 4275);
DISPLAY 1.021277 (-4750 4275);
PAINT ORANGE (-4750 4275);
DISPLAY INVISIBLE (-4750 4275);
FORCEPROP 2 LAST CDS_LOCATION R7D4
J 0
(-4750 4175);
DISPLAY 0.617021 (-4750 4175);
PAINT AQUA (-4750 4175);
DISPLAY INVISIBLE (-4750 4175);
FORCEPROP 1 LAST PATH I245
J 0
(-4750 4275);
DISPLAY 0.978723 (-4750 4275);
PAINT WHITE (-4750 4275);
DISPLAY INVISIBLE (-4750 4275);
FORCEPROP 2 LAST CDS_LIB mstr_discrete
J 0
(-4700 4125);
PAINT ORANGE (-4700 4125);
DISPLAY INVISIBLE (-4700 4125);
FORCEPROP 2 LAST SEC_TYPE 0402
J 0
(-4750 4325);
DISPLAY 1.021277 (-4750 4325);
PAINT ORANGE (-4750 4325);
DISPLAY INVISIBLE (-4750 4325);
FORCEPROP 2 LAST SEC 1
J 0
(-4750 4325);
DISPLAY 0.680851 (-4750 4325);
PAINT MONO (-4750 4325);
DISPLAY INVISIBLE (-4750 4325);
FORCEADD OFFPAGE..2
(-3850 4125);
FORCEPROP 2 LAST $XR0 119 
J 0
(-3661 4125);
DISPLAY 0.638298 (-3661 4125);
PAINT MONO (-3661 4125);
FORCEPROP 1 LAST COMMENT_BODY TRUE
J 0
(-3895 4030);
DISPLAY 0.872340 (-3895 4030);
PAINT GREEN (-3895 4030);
DISPLAY INVISIBLE (-3895 4030);
FORCEPROP 1 LAST OFFPAGE TRUE
J 0
(-3525 4000);
DISPLAY 0.872340 (-3525 4000);
PAINT GREEN (-3525 4000);
DISPLAY INVISIBLE (-3525 4000);
FORCEPROP 2 LAST CDS_LIB mstr_standard
J 0
(-3850 4125);
PAINT ORANGE (-3850 4125);
DISPLAY INVISIBLE (-3850 4125);
FORCEPROP 2 LAST PATH I246
J 0
(-3625 4175);
DISPLAY 1.021277 (-3625 4175);
PAINT ORANGE (-3625 4175);
DISPLAY INVISIBLE (-3625 4175);
FORCEADD RES..1
(-4650 2725);
FORCEPROP 1 LAST WATTAGE 1/16W
J 2
(-4720 2635);
DISPLAY 0.617021 (-4720 2635);
PAINT SKYBLUE (-4720 2635);
FORCEPROP 1 LAST VALUE 10.0K
J 2
(-4675 2675);
DISPLAY 0.617021 (-4675 2675);
PAINT SKYBLUE (-4675 2675);
FORCEPROP 1 LAST LOCATION R2N16
J 0
(-4800 2775);
DISPLAY 0.617021 (-4800 2775);
PAINT AQUA (-4800 2775);
FORCEPROP 1 LASTPIN (-4750 2725) $PN 1
J 0
(-4738 2737);
DISPLAY 0.617021 (-4738 2737);
PAINT MONO (-4738 2737);
FORCEPROP 1 LAST TOLERANCE 1%
J 0
(-4620 2675);
DISPLAY 0.617021 (-4620 2675);
PAINT SKYBLUE (-4620 2675);
FORCEPROP 1 LAST MATERIAL CHIP
J 0
(-4710 2635);
DISPLAY 0.617021 (-4710 2635);
PAINT SKYBLUE (-4710 2635);
FORCEPROP 1 LAST PART_NUMBER G21796-016
J 0
(-4575 2775);
DISPLAY 0.617021 (-4575 2775);
PAINT BLUE (-4575 2775);
FORCEPROP 1 LAST PACK_TYPE 0402
J 0
(-4540 2685);
DISPLAY 0.617021 (-4540 2685);
PAINT SKYBLUE (-4540 2685);
FORCEPROP 1 LASTPIN (-4550 2725) $PN 2
J 0
(-4588 2737);
DISPLAY 0.617021 (-4588 2737);
PAINT MONO (-4588 2737);
FORCEPROP 2 LAST CDS_LOCATION R2N16
J 0
(-4800 2775);
DISPLAY 0.617021 (-4800 2775);
PAINT AQUA (-4800 2775);
DISPLAY INVISIBLE (-4800 2775);
FORCEPROP 2 LAST ROOM SB
J 0
(-4650 2725);
PAINT MONO (-4650 2725);
DISPLAY INVISIBLE (-4650 2725);
FORCEPROP 2 LAST CDS_LIB mstr_discrete
J 0
(-4650 2725);
PAINT MONO (-4650 2725);
DISPLAY INVISIBLE (-4650 2725);
FORCEPROP 2 LAST BOM_COST SB
J 0
(-4700 2575);
PAINT MONO (-4700 2575);
DISPLAY INVISIBLE (-4700 2575);
FORCEPROP 2 LAST CDS_SEC 1
J 0
(-4700 2925);
DISPLAY 1.404255 (-4700 2925);
PAINT ORANGE (-4700 2925);
DISPLAY INVISIBLE (-4700 2925);
FORCEPROP 2 LAST $SEC 1
J 0
(-4700 2925);
DISPLAY 0.936170 (-4700 2925);
PAINT MONO (-4700 2925);
DISPLAY INVISIBLE (-4700 2925);
FORCEPROP 1 LAST PATH I247
J 0
(-4700 2875);
DISPLAY 0.978723 (-4700 2875);
PAINT WHITE (-4700 2875);
DISPLAY INVISIBLE (-4700 2875);
FORCEADD OFFPAGE..2
(-3700 2725);
FORCEPROP 2 LAST $XR0 119 
J 0
(-3511 2725);
DISPLAY 0.638298 (-3511 2725);
PAINT MONO (-3511 2725);
FORCEPROP 1 LAST COMMENT_BODY TRUE
J 0
(-3745 2630);
DISPLAY 1.170213 (-3745 2630);
PAINT GREEN (-3745 2630);
DISPLAY INVISIBLE (-3745 2630);
FORCEPROP 2 LAST CDS_LIB mstr_standard
J 0
(-3700 2725);
PAINT MONO (-3700 2725);
DISPLAY INVISIBLE (-3700 2725);
FORCEPROP 2 LAST PATH I248
J 0
(-3500 2775);
DISPLAY 1.021277 (-3500 2775);
PAINT ORANGE (-3500 2775);
DISPLAY INVISIBLE (-3500 2775);
FORCEPROP 1 LAST OFFPAGE TRUE
J 0
(-3375 2600);
PAINT GREEN (-3375 2600);
DISPLAY INVISIBLE (-3375 2600);
FORCEPROP 2 LAST BOM_COST SB
J 0
(-3500 2775);
PAINT MONO (-3500 2775);
DISPLAY INVISIBLE (-3500 2775);
FORCEADD P3V3_STBY..1
(-4950 2925);
FORCEPROP 3 LASTPIN (-4950 2875) SIG_NAME P3V3_STBY\g
J 0
(-4940 2885);
DISPLAY 0.659574 (-4940 2885);
PAINT MONO (-4940 2885);
DISPLAY INVISIBLE (-4940 2885);
FORCEPROP 1 LAST HDL_POWER P3V3_STBY
J 0
(-5250 2800);
DISPLAY 0.872340 (-5250 2800);
PAINT ORANGE (-5250 2800);
DISPLAY INVISIBLE (-5250 2800);
FORCEPROP 1 LAST PATH I251
J 0
(-4905 2927);
DISPLAY 0.340426 (-4905 2927);
PAINT GREEN (-4905 2927);
DISPLAY INVISIBLE (-4905 2927);
FORCEPROP 1 LAST BODY_TYPE PLUMBING
J 0
(-4995 2882);
DISPLAY 0.340426 (-4995 2882);
PAINT GREEN (-4995 2882);
DISPLAY INVISIBLE (-4995 2882);
FORCEPROP 1 LAST SIZE 1B
J 0
(-4905 2947);
DISPLAY 0.340426 (-4905 2947);
PAINT GREEN (-4905 2947);
DISPLAY INVISIBLE (-4905 2947);
FORCEPROP 2 LAST CDS_LIB mstr_symbols
J 0
(-4950 2925);
PAINT MONO (-4950 2925);
DISPLAY INVISIBLE (-4950 2925);
FORCEPROP 1 LAST VOLTAGE 3.3V
J 0
(-4995 2882);
DISPLAY 0.340426 (-4995 2882);
PAINT SKYBLUE (-4995 2882);
DISPLAY INVISIBLE (-4995 2882);
FORCEADD OFFPAGE..2
(-3925 1825);
FORCEPROP 2 LAST $XR0 120 
J 0
(-3736 1825);
DISPLAY 0.638298 (-3736 1825);
PAINT MONO (-3736 1825);
FORCEPROP 2 LAST $XR1 146 
J 0
(-3616 1825);
DISPLAY 0.638298 (-3616 1825);
PAINT MONO (-3616 1825);
FORCEPROP 2 LAST $XR2 119 
J 0
(-3496 1825);
DISPLAY 0.638298 (-3496 1825);
PAINT MONO (-3496 1825);
FORCEPROP 1 LAST COMMENT_BODY TRUE
J 0
(-3970 1730);
DISPLAY 1.170213 (-3970 1730);
PAINT GREEN (-3970 1730);
DISPLAY INVISIBLE (-3970 1730);
FORCEPROP 2 LAST CDS_LIB mstr_standard
J 0
(-3925 1825);
PAINT MONO (-3925 1825);
DISPLAY INVISIBLE (-3925 1825);
FORCEPROP 1 LAST OFFPAGE TRUE
J 0
(-3600 1700);
PAINT GREEN (-3600 1700);
DISPLAY INVISIBLE (-3600 1700);
FORCEPROP 2 LAST BOM_COST SB
J 0
(-3725 1875);
PAINT MONO (-3725 1875);
DISPLAY INVISIBLE (-3725 1875);
FORCEPROP 2 LAST PATH I254
J 0
(-3475 1875);
DISPLAY 1.021277 (-3475 1875);
PAINT ORANGE (-3475 1875);
DISPLAY INVISIBLE (-3475 1875);
FORCEADD P3V3_STBY..1
(-5075 1975);
FORCEPROP 3 LASTPIN (-5075 1925) SIG_NAME P3V3_STBY\g
J 0
(-5065 1935);
DISPLAY 0.659574 (-5065 1935);
PAINT MONO (-5065 1935);
DISPLAY INVISIBLE (-5065 1935);
FORCEPROP 1 LAST HDL_POWER P3V3_STBY
J 0
(-5375 1850);
DISPLAY 0.872340 (-5375 1850);
PAINT ORANGE (-5375 1850);
DISPLAY INVISIBLE (-5375 1850);
FORCEPROP 1 LAST VOLTAGE 3.3V
J 0
(-5120 1932);
DISPLAY 0.340426 (-5120 1932);
PAINT SKYBLUE (-5120 1932);
DISPLAY INVISIBLE (-5120 1932);
FORCEPROP 1 LAST BODY_TYPE PLUMBING
J 0
(-5120 1932);
DISPLAY 0.340426 (-5120 1932);
PAINT GREEN (-5120 1932);
DISPLAY INVISIBLE (-5120 1932);
FORCEPROP 2 LAST CDS_LIB mstr_symbols
J 0
(-5075 1975);
PAINT MONO (-5075 1975);
DISPLAY INVISIBLE (-5075 1975);
FORCEPROP 1 LAST SIZE 1B
J 0
(-5030 1997);
DISPLAY 0.340426 (-5030 1997);
PAINT GREEN (-5030 1997);
DISPLAY INVISIBLE (-5030 1997);
FORCEPROP 1 LAST PATH I256
J 0
(-5030 1977);
DISPLAY 0.340426 (-5030 1977);
PAINT GREEN (-5030 1977);
DISPLAY INVISIBLE (-5030 1977);
FORCEADD OFFPAGE..2
(-3925 1650);
FORCEPROP 2 LAST $XR0 119 
J 0
(-3736 1650);
DISPLAY 0.638298 (-3736 1650);
PAINT MONO (-3736 1650);
FORCEPROP 2 LAST $XR1 170 
J 0
(-3616 1650);
DISPLAY 0.638298 (-3616 1650);
PAINT MONO (-3616 1650);
FORCEPROP 2 LAST $XR2 95 
J 0
(-3496 1650);
DISPLAY 0.638298 (-3496 1650);
PAINT MONO (-3496 1650);
FORCEPROP 2 LAST $XR3 120 
J 0
(-3406 1650);
DISPLAY 0.638298 (-3406 1650);
PAINT MONO (-3406 1650);
FORCEPROP 2 LAST $XR4 146 
J 0
(-3286 1650);
DISPLAY 0.638298 (-3286 1650);
PAINT MONO (-3286 1650);
FORCEPROP 2 LAST $XR5 ?
J 0
(-3286 1650);
DISPLAY 0.638298 (-3286 1650);
PAINT MONO (-3286 1650);
FORCEPROP 1 LAST OFFPAGE TRUE
J 0
(-3600 1525);
PAINT GREEN (-3600 1525);
DISPLAY INVISIBLE (-3600 1525);
FORCEPROP 2 LAST CDS_LIB mstr_standard
J 0
(-3925 1650);
PAINT MONO (-3925 1650);
DISPLAY INVISIBLE (-3925 1650);
FORCEPROP 1 LAST COMMENT_BODY TRUE
J 0
(-3970 1555);
DISPLAY 1.170213 (-3970 1555);
PAINT GREEN (-3970 1555);
DISPLAY INVISIBLE (-3970 1555);
FORCEPROP 2 LAST PATH I257
J 0
(-3750 1725);
DISPLAY 1.021277 (-3750 1725);
PAINT ORANGE (-3750 1725);
DISPLAY INVISIBLE (-3750 1725);
FORCEPROP 2 LAST BOM_COST SB
J 0
(-3725 1700);
PAINT MONO (-3725 1700);
DISPLAY INVISIBLE (-3725 1700);
FORCEADD RES..1
(-2600 5125);
FORCEPROP 1 LAST VALUE 1.00K
J 2
(-2625 5075);
DISPLAY 0.617021 (-2625 5075);
PAINT SKYBLUE (-2625 5075);
FORCEPROP 1 LAST TOLERANCE 1%
J 0
(-2570 5075);
DISPLAY 0.617021 (-2570 5075);
PAINT SKYBLUE (-2570 5075);
FORCEPROP 1 LAST PACK_TYPE 0402
J 0
(-2490 5085);
DISPLAY 0.617021 (-2490 5085);
PAINT SKYBLUE (-2490 5085);
FORCEPROP 1 LAST MATERIAL CHIP
J 0
(-2385 5085);
DISPLAY 0.617021 (-2385 5085);
PAINT SKYBLUE (-2385 5085);
FORCEPROP 1 LAST WATTAGE 1/16W
J 2
(-2120 5085);
DISPLAY 0.617021 (-2120 5085);
PAINT SKYBLUE (-2120 5085);
FORCEPROP 1 LAST LOCATION R2R5
J 0
(-2825 5175);
DISPLAY 0.617021 (-2825 5175);
PAINT AQUA (-2825 5175);
FORCEPROP 1 LASTPIN (-2700 5125) $PN 1
J 0
(-2688 5137);
DISPLAY 0.617021 (-2688 5137);
PAINT ORANGE (-2688 5137);
FORCEPROP 1 LAST PART_NUMBER G21796-026
J 0
(-2500 5150);
DISPLAY 0.617021 (-2500 5150);
PAINT BLUE (-2500 5150);
FORCEPROP 1 LASTPIN (-2500 5125) $PN 2
J 0
(-2538 5137);
DISPLAY 0.617021 (-2538 5137);
PAINT ORANGE (-2538 5137);
FORCEPROP 2 LAST BOM_COST SB
J 0
(-2650 4975);
PAINT MONO (-2650 4975);
DISPLAY INVISIBLE (-2650 4975);
FORCEPROP 2 LAST CDS_LOCATION R2R5
J 0
(-2825 5175);
DISPLAY 0.617021 (-2825 5175);
PAINT AQUA (-2825 5175);
DISPLAY INVISIBLE (-2825 5175);
FORCEPROP 2 LAST ROOM SB
J 0
(-2600 5125);
PAINT MONO (-2600 5125);
DISPLAY INVISIBLE (-2600 5125);
FORCEPROP 2 LAST CDS_LIB mstr_discrete
J 0
(-2600 5125);
PAINT ORANGE (-2600 5125);
DISPLAY INVISIBLE (-2600 5125);
FORCEPROP 2 LAST SEC_TYPE 0402
J 0
(-2650 5325);
DISPLAY 1.021277 (-2650 5325);
PAINT ORANGE (-2650 5325);
DISPLAY INVISIBLE (-2650 5325);
FORCEPROP 2 LAST SEC 1
J 0
(-2650 5325);
DISPLAY 0.680851 (-2650 5325);
PAINT MONO (-2650 5325);
DISPLAY INVISIBLE (-2650 5325);
FORCEPROP 1 LAST PATH I258
J 0
(-2650 5275);
DISPLAY 0.978723 (-2650 5275);
PAINT WHITE (-2650 5275);
DISPLAY INVISIBLE (-2650 5275);
FORCEADD OFFPAGE..2
(-1700 5125);
FORCEPROP 2 LAST $XR0 119 
J 0
(-1511 5125);
DISPLAY 0.638298 (-1511 5125);
PAINT MONO (-1511 5125);
FORCEPROP 2 LAST $XR1 190 
J 0
(-1391 5125);
DISPLAY 0.638298 (-1391 5125);
PAINT MONO (-1391 5125);
FORCEPROP 1 LAST COMMENT_BODY TRUE
J 0
(-1745 5030);
DISPLAY 1.170213 (-1745 5030);
PAINT GREEN (-1745 5030);
DISPLAY INVISIBLE (-1745 5030);
FORCEPROP 1 LAST OFFPAGE TRUE
J 0
(-1375 5000);
PAINT GREEN (-1375 5000);
DISPLAY INVISIBLE (-1375 5000);
FORCEPROP 2 LAST CDS_LIB mstr_standard
J 0
(-1700 5125);
PAINT ORANGE (-1700 5125);
DISPLAY INVISIBLE (-1700 5125);
FORCEPROP 2 LAST BOM_COST SB
J 0
(-1500 5175);
PAINT MONO (-1500 5175);
DISPLAY INVISIBLE (-1500 5175);
FORCEPROP 2 LAST PATH I259
J 0
(-1375 5175);
DISPLAY 1.021277 (-1375 5175);
PAINT ORANGE (-1375 5175);
DISPLAY INVISIBLE (-1375 5175);
FORCEADD P3V3_STBY..1
(-2825 5350);
FORCEPROP 3 LASTPIN (-2825 5300) SIG_NAME P3V3_STBY\g
J 0
(-2815 5310);
DISPLAY 0.659574 (-2815 5310);
PAINT MONO (-2815 5310);
DISPLAY INVISIBLE (-2815 5310);
FORCEPROP 1 LAST HDL_POWER P3V3_STBY
J 0
(-3125 5225);
DISPLAY 0.872340 (-3125 5225);
PAINT ORANGE (-3125 5225);
DISPLAY INVISIBLE (-3125 5225);
FORCEPROP 1 LAST BODY_TYPE PLUMBING
J 0
(-2870 5307);
DISPLAY 0.340426 (-2870 5307);
PAINT GREEN (-2870 5307);
DISPLAY INVISIBLE (-2870 5307);
FORCEPROP 1 LAST VOLTAGE 3.3V
J 0
(-2870 5307);
DISPLAY 0.340426 (-2870 5307);
PAINT SKYBLUE (-2870 5307);
DISPLAY INVISIBLE (-2870 5307);
FORCEPROP 2 LAST CDS_LIB mstr_symbols
J 0
(-2825 5350);
PAINT MONO (-2825 5350);
DISPLAY INVISIBLE (-2825 5350);
FORCEPROP 1 LAST SIZE 1B
J 0
(-2780 5372);
DISPLAY 0.340426 (-2780 5372);
PAINT GREEN (-2780 5372);
DISPLAY INVISIBLE (-2780 5372);
FORCEPROP 1 LAST PATH I260
J 0
(-2780 5352);
DISPLAY 0.340426 (-2780 5352);
PAINT GREEN (-2780 5352);
DISPLAY INVISIBLE (-2780 5352);
FORCEADD OFFPAGE..2
(-1650 1275);
FORCEPROP 2 LAST $XR0 120 
J 0
(-1461 1275);
DISPLAY 0.638298 (-1461 1275);
PAINT MONO (-1461 1275);
FORCEPROP 1 LAST COMMENT_BODY TRUE
J 0
(-1695 1180);
DISPLAY 1.170213 (-1695 1180);
PAINT GREEN (-1695 1180);
DISPLAY INVISIBLE (-1695 1180);
FORCEPROP 2 LAST CDS_LIB mstr_standard
J 0
(-1650 1275);
PAINT MONO (-1650 1275);
DISPLAY INVISIBLE (-1650 1275);
FORCEPROP 1 LAST OFFPAGE TRUE
J 0
(-1325 1150);
PAINT GREEN (-1325 1150);
DISPLAY INVISIBLE (-1325 1150);
FORCEPROP 2 LAST BOM_COST SB
J 0
(-1450 1325);
PAINT MONO (-1450 1325);
DISPLAY INVISIBLE (-1450 1325);
FORCEPROP 2 LAST PATH I264
J 0
(-1475 1350);
DISPLAY 1.021277 (-1475 1350);
PAINT ORANGE (-1475 1350);
DISPLAY INVISIBLE (-1475 1350);
FORCEADD RES..1
(-2475 1275);
FORCEPROP 1 LAST WATTAGE 1/16W
J 2
(-2600 1175);
DISPLAY 0.617021 (-2600 1175);
PAINT SKYBLUE (-2600 1175);
FORCEPROP 1 LAST VALUE 10.0K
J 2
(-2550 1225);
DISPLAY 0.617021 (-2550 1225);
PAINT SKYBLUE (-2550 1225);
FORCEPROP 1 LASTPIN (-2575 1275) $PN 1
J 0
(-2563 1287);
DISPLAY 0.617021 (-2563 1287);
PAINT ORANGE (-2563 1287);
FORCEPROP 1 LAST TOLERANCE 1%
J 0
(-2500 1200);
DISPLAY 0.617021 (-2500 1200);
PAINT SKYBLUE (-2500 1200);
FORCEPROP 1 LAST MATERIAL CHIP
J 0
(-2425 1200);
DISPLAY 0.617021 (-2425 1200);
PAINT SKYBLUE (-2425 1200);
FORCEPROP 1 LAST LOCATION R2N9
J 0
(-2525 1325);
DISPLAY 0.617021 (-2525 1325);
PAINT AQUA (-2525 1325);
FORCEPROP 1 LASTPIN (-2375 1275) $PN 2
J 0
(-2413 1287);
DISPLAY 0.617021 (-2413 1287);
PAINT ORANGE (-2413 1287);
FORCEPROP 1 LAST PART_NUMBER G21796-016
J 0
(-2525 1375);
DISPLAY 0.617021 (-2525 1375);
PAINT BLUE (-2525 1375);
FORCEPROP 1 LAST PACK_TYPE 0402
J 0
(-2375 1225);
DISPLAY 0.617021 (-2375 1225);
PAINT SKYBLUE (-2375 1225);
FORCEPROP 2 LAST CDS_LIB mstr_discrete
J 0
(-2475 1275);
PAINT MONO (-2475 1275);
DISPLAY INVISIBLE (-2475 1275);
FORCEPROP 2 LAST SEC_TYPE 0402
J 0
(-2525 1475);
DISPLAY 1.021277 (-2525 1475);
PAINT ORANGE (-2525 1475);
DISPLAY INVISIBLE (-2525 1475);
FORCEPROP 2 LAST SEC 1
J 0
(-2525 1475);
DISPLAY 0.680851 (-2525 1475);
PAINT MONO (-2525 1475);
DISPLAY INVISIBLE (-2525 1475);
FORCEPROP 2 LAST CDS_LOCATION R2N9
J 0
(-2525 1325);
DISPLAY 0.617021 (-2525 1325);
PAINT AQUA (-2525 1325);
DISPLAY INVISIBLE (-2525 1325);
FORCEPROP 1 LAST PATH I267
J 0
(-2525 1425);
DISPLAY 0.978723 (-2525 1425);
PAINT WHITE (-2525 1425);
DISPLAY INVISIBLE (-2525 1425);
FORCEPROP 0 LAST ROOM SB
J 0
(-2425 1500);
DISPLAY 1.021277 (-2425 1500);
PAINT ORANGE (-2425 1500);
DISPLAY INVISIBLE (-2425 1500);
FORCEADD P3V3_STBY..1
(-2750 1425);
FORCEPROP 3 LASTPIN (-2750 1375) SIG_NAME P3V3_STBY\g
J 0
(-2740 1385);
DISPLAY 0.659574 (-2740 1385);
PAINT MONO (-2740 1385);
DISPLAY INVISIBLE (-2740 1385);
FORCEPROP 1 LAST HDL_POWER P3V3_STBY
J 0
(-3050 1300);
DISPLAY 0.872340 (-3050 1300);
PAINT ORANGE (-3050 1300);
DISPLAY INVISIBLE (-3050 1300);
FORCEPROP 1 LAST VOLTAGE 3.3V
J 0
(-2795 1382);
DISPLAY 0.340426 (-2795 1382);
PAINT SKYBLUE (-2795 1382);
DISPLAY INVISIBLE (-2795 1382);
FORCEPROP 1 LAST BODY_TYPE PLUMBING
J 0
(-2795 1382);
DISPLAY 0.340426 (-2795 1382);
PAINT GREEN (-2795 1382);
DISPLAY INVISIBLE (-2795 1382);
FORCEPROP 1 LAST PATH I268
J 0
(-2705 1427);
DISPLAY 0.340426 (-2705 1427);
PAINT GREEN (-2705 1427);
DISPLAY INVISIBLE (-2705 1427);
FORCEPROP 2 LAST CDS_LIB mstr_symbols
J 0
(-2750 1425);
PAINT MONO (-2750 1425);
DISPLAY INVISIBLE (-2750 1425);
FORCEPROP 1 LAST SIZE 1B
J 0
(-2705 1447);
DISPLAY 0.340426 (-2705 1447);
PAINT GREEN (-2705 1447);
DISPLAY INVISIBLE (-2705 1447);
FORCEADD OFFPAGE..2
(-3700 2400);
FORCEPROP 2 LAST $XR0 119 
J 0
(-3511 2400);
DISPLAY 0.638298 (-3511 2400);
PAINT MONO (-3511 2400);
FORCEPROP 2 LAST $XR1 146 
J 0
(-3391 2400);
DISPLAY 0.638298 (-3391 2400);
PAINT MONO (-3391 2400);
FORCEPROP 2 LAST CDS_LIB mstr_standard
J 0
(-3700 2400);
PAINT MONO (-3700 2400);
DISPLAY INVISIBLE (-3700 2400);
FORCEPROP 1 LAST COMMENT_BODY TRUE
J 0
(-3745 2305);
DISPLAY 1.170213 (-3745 2305);
PAINT GREEN (-3745 2305);
DISPLAY INVISIBLE (-3745 2305);
FORCEPROP 2 LAST PATH I279
J 0
(-3525 2475);
DISPLAY 1.021277 (-3525 2475);
PAINT ORANGE (-3525 2475);
DISPLAY INVISIBLE (-3525 2475);
FORCEPROP 1 LAST OFFPAGE TRUE
J 0
(-3375 2275);
PAINT GREEN (-3375 2275);
DISPLAY INVISIBLE (-3375 2275);
FORCEPROP 2 LAST BOM_COST SB
J 0
(-3500 2450);
PAINT MONO (-3500 2450);
DISPLAY INVISIBLE (-3500 2450);
FORCEADD RES..1
(-2575 4675);
FORCEPROP 1 LAST VALUE 1.00K
J 2
(-2600 4625);
DISPLAY 0.617021 (-2600 4625);
PAINT SKYBLUE (-2600 4625);
FORCEPROP 1 LAST LOCATION R8B23
J 0
(-2800 4725);
DISPLAY 0.617021 (-2800 4725);
PAINT AQUA (-2800 4725);
FORCEPROP 1 LASTPIN (-2675 4675) $PN 1
J 0
(-2663 4687);
DISPLAY 0.617021 (-2663 4687);
PAINT ORANGE (-2663 4687);
FORCEPROP 1 LASTPIN (-2475 4675) $PN 2
J 0
(-2513 4687);
DISPLAY 0.617021 (-2513 4687);
PAINT ORANGE (-2513 4687);
FORCEPROP 1 LAST PACK_TYPE 0402
J 0
(-2465 4635);
DISPLAY 0.617021 (-2465 4635);
PAINT SKYBLUE (-2465 4635);
FORCEPROP 1 LAST TOLERANCE 1%
J 0
(-2545 4625);
DISPLAY 0.617021 (-2545 4625);
PAINT SKYBLUE (-2545 4625);
FORCEPROP 1 LAST MATERIAL CHIP
J 0
(-2360 4635);
DISPLAY 0.617021 (-2360 4635);
PAINT SKYBLUE (-2360 4635);
FORCEPROP 1 LAST PART_NUMBER G21796-026
J 0
(-2475 4700);
DISPLAY 0.617021 (-2475 4700);
PAINT BLUE (-2475 4700);
FORCEPROP 1 LAST WATTAGE 1/16W
J 2
(-2095 4635);
DISPLAY 0.617021 (-2095 4635);
PAINT SKYBLUE (-2095 4635);
FORCEPROP 2 LAST BOM_COST SB
J 0
(-2625 4525);
PAINT MONO (-2625 4525);
DISPLAY INVISIBLE (-2625 4525);
FORCEPROP 2 LAST CDS_LOCATION R8B23
J 0
(-2800 4725);
DISPLAY 0.617021 (-2800 4725);
PAINT AQUA (-2800 4725);
DISPLAY INVISIBLE (-2800 4725);
FORCEPROP 2 LAST CDS_LIB mstr_discrete
J 0
(-2575 4675);
PAINT MONO (-2575 4675);
DISPLAY INVISIBLE (-2575 4675);
FORCEPROP 2 LAST ROOM SB
J 0
(-2575 4675);
PAINT MONO (-2575 4675);
DISPLAY INVISIBLE (-2575 4675);
FORCEPROP 1 LAST PATH I280
J 0
(-2625 4825);
DISPLAY 0.978723 (-2625 4825);
PAINT WHITE (-2625 4825);
DISPLAY INVISIBLE (-2625 4825);
FORCEPROP 2 LAST SEC 1
J 0
(-2625 4875);
DISPLAY 0.680851 (-2625 4875);
PAINT MONO (-2625 4875);
DISPLAY INVISIBLE (-2625 4875);
FORCEPROP 2 LAST SEC_TYPE 0402
J 0
(-2625 4875);
DISPLAY 1.021277 (-2625 4875);
PAINT ORANGE (-2625 4875);
DISPLAY INVISIBLE (-2625 4875);
FORCEADD OFFPAGE..2
(-1675 4675);
FORCEPROP 2 LAST $XR0 182 
J 0
(-1486 4675);
DISPLAY 0.638298 (-1486 4675);
PAINT MONO (-1486 4675);
FORCEPROP 2 LAST $XR1 119 
J 0
(-1366 4675);
DISPLAY 0.638298 (-1366 4675);
PAINT MONO (-1366 4675);
FORCEPROP 2 LAST $XR2 147 
J 0
(-1246 4675);
DISPLAY 0.638298 (-1246 4675);
PAINT MONO (-1246 4675);
FORCEPROP 1 LAST COMMENT_BODY TRUE
J 0
(-1720 4580);
DISPLAY 1.170213 (-1720 4580);
PAINT GREEN (-1720 4580);
DISPLAY INVISIBLE (-1720 4580);
FORCEPROP 2 LAST CDS_LIB mstr_standard
J 0
(-1675 4675);
PAINT MONO (-1675 4675);
DISPLAY INVISIBLE (-1675 4675);
FORCEPROP 1 LAST OFFPAGE TRUE
J 0
(-1350 4550);
PAINT GREEN (-1350 4550);
DISPLAY INVISIBLE (-1350 4550);
FORCEPROP 2 LAST PATH I281
J 0
(-1500 4750);
DISPLAY 1.021277 (-1500 4750);
PAINT ORANGE (-1500 4750);
DISPLAY INVISIBLE (-1500 4750);
FORCEPROP 2 LAST BOM_COST SB
J 0
(-1475 4725);
PAINT MONO (-1475 4725);
DISPLAY INVISIBLE (-1475 4725);
FORCEADD RES..1
(-2575 4425);
FORCEPROP 1 LAST VALUE 1.00K
J 2
(-2600 4375);
DISPLAY 0.617021 (-2600 4375);
PAINT SKYBLUE (-2600 4375);
FORCEPROP 1 LAST LOCATION R8B30
J 0
(-2800 4475);
DISPLAY 0.617021 (-2800 4475);
PAINT AQUA (-2800 4475);
FORCEPROP 1 LASTPIN (-2675 4425) $PN 1
J 0
(-2663 4437);
DISPLAY 0.617021 (-2663 4437);
PAINT ORANGE (-2663 4437);
FORCEPROP 1 LAST TOLERANCE 1%
J 0
(-2545 4375);
DISPLAY 0.617021 (-2545 4375);
PAINT SKYBLUE (-2545 4375);
FORCEPROP 1 LAST PACK_TYPE 0402
J 0
(-2465 4385);
DISPLAY 0.617021 (-2465 4385);
PAINT SKYBLUE (-2465 4385);
FORCEPROP 1 LASTPIN (-2475 4425) $PN 2
J 0
(-2513 4437);
DISPLAY 0.617021 (-2513 4437);
PAINT ORANGE (-2513 4437);
FORCEPROP 1 LAST PART_NUMBER G21796-026
J 0
(-2475 4450);
DISPLAY 0.617021 (-2475 4450);
PAINT BLUE (-2475 4450);
FORCEPROP 1 LAST MATERIAL CHIP
J 0
(-2360 4385);
DISPLAY 0.617021 (-2360 4385);
PAINT SKYBLUE (-2360 4385);
FORCEPROP 1 LAST WATTAGE 1/16W
J 2
(-2095 4385);
DISPLAY 0.617021 (-2095 4385);
PAINT SKYBLUE (-2095 4385);
FORCEPROP 2 LAST BOM_COST SB
J 0
(-2625 4275);
PAINT MONO (-2625 4275);
DISPLAY INVISIBLE (-2625 4275);
FORCEPROP 2 LAST CDS_LIB mstr_discrete
J 0
(-2575 4425);
PAINT MONO (-2575 4425);
DISPLAY INVISIBLE (-2575 4425);
FORCEPROP 2 LAST ROOM SB
J 0
(-2575 4425);
PAINT MONO (-2575 4425);
DISPLAY INVISIBLE (-2575 4425);
FORCEPROP 2 LAST CDS_LOCATION R8B30
J 0
(-2800 4475);
DISPLAY 0.617021 (-2800 4475);
PAINT AQUA (-2800 4475);
DISPLAY INVISIBLE (-2800 4475);
FORCEPROP 1 LAST PATH I282
J 0
(-2625 4575);
DISPLAY 0.978723 (-2625 4575);
PAINT WHITE (-2625 4575);
DISPLAY INVISIBLE (-2625 4575);
FORCEPROP 2 LAST SEC 1
J 0
(-2625 4625);
DISPLAY 0.680851 (-2625 4625);
PAINT MONO (-2625 4625);
DISPLAY INVISIBLE (-2625 4625);
FORCEPROP 2 LAST SEC_TYPE 0402
J 0
(-2625 4625);
DISPLAY 1.021277 (-2625 4625);
PAINT ORANGE (-2625 4625);
DISPLAY INVISIBLE (-2625 4625);
FORCEADD OFFPAGE..2
(-1675 4425);
FORCEPROP 2 LAST $XR0 182 
J 0
(-1486 4425);
DISPLAY 0.638298 (-1486 4425);
PAINT MONO (-1486 4425);
FORCEPROP 2 LAST $XR1 119 
J 0
(-1366 4425);
DISPLAY 0.638298 (-1366 4425);
PAINT MONO (-1366 4425);
FORCEPROP 2 LAST $XR2 147 
J 0
(-1246 4425);
DISPLAY 0.638298 (-1246 4425);
PAINT MONO (-1246 4425);
FORCEPROP 1 LAST COMMENT_BODY TRUE
J 0
(-1720 4330);
DISPLAY 1.170213 (-1720 4330);
PAINT GREEN (-1720 4330);
DISPLAY INVISIBLE (-1720 4330);
FORCEPROP 2 LAST CDS_LIB mstr_standard
J 0
(-1675 4425);
PAINT MONO (-1675 4425);
DISPLAY INVISIBLE (-1675 4425);
FORCEPROP 2 LAST BOM_COST SB
J 0
(-1475 4475);
PAINT MONO (-1475 4475);
DISPLAY INVISIBLE (-1475 4475);
FORCEPROP 1 LAST OFFPAGE TRUE
J 0
(-1350 4300);
PAINT GREEN (-1350 4300);
DISPLAY INVISIBLE (-1350 4300);
FORCEPROP 2 LAST PATH I283
J 0
(-1500 4500);
DISPLAY 1.021277 (-1500 4500);
PAINT ORANGE (-1500 4500);
DISPLAY INVISIBLE (-1500 4500);
FORCEADD RES..1
(-2600 4900);
FORCEPROP 1 LAST LOCATION R2M4
J 0
(-2825 4950);
DISPLAY 0.617021 (-2825 4950);
PAINT AQUA (-2825 4950);
FORCEPROP 1 LAST VALUE 1.00K
J 2
(-2625 4850);
DISPLAY 0.617021 (-2625 4850);
PAINT SKYBLUE (-2625 4850);
FORCEPROP 1 LASTPIN (-2700 4900) $PN 1
J 0
(-2688 4912);
DISPLAY 0.617021 (-2688 4912);
PAINT ORANGE (-2688 4912);
FORCEPROP 1 LAST TOLERANCE 1%
J 0
(-2570 4850);
DISPLAY 0.617021 (-2570 4850);
PAINT SKYBLUE (-2570 4850);
FORCEPROP 1 LASTPIN (-2500 4900) $PN 2
J 0
(-2538 4912);
DISPLAY 0.617021 (-2538 4912);
PAINT ORANGE (-2538 4912);
FORCEPROP 1 LAST PACK_TYPE 0402
J 0
(-2490 4860);
DISPLAY 0.617021 (-2490 4860);
PAINT SKYBLUE (-2490 4860);
FORCEPROP 1 LAST MATERIAL CHIP
J 0
(-2385 4860);
DISPLAY 0.617021 (-2385 4860);
PAINT SKYBLUE (-2385 4860);
FORCEPROP 1 LAST PART_NUMBER G21796-026
J 0
(-2500 4925);
DISPLAY 0.617021 (-2500 4925);
PAINT BLUE (-2500 4925);
FORCEPROP 1 LAST WATTAGE 1/16W
J 2
(-2120 4860);
DISPLAY 0.617021 (-2120 4860);
PAINT SKYBLUE (-2120 4860);
FORCEPROP 2 LAST CDS_LOCATION R2M4
J 0
(-2825 4950);
DISPLAY 0.617021 (-2825 4950);
PAINT AQUA (-2825 4950);
DISPLAY INVISIBLE (-2825 4950);
FORCEPROP 2 LAST BOM_COST SB
J 0
(-2650 4750);
PAINT MONO (-2650 4750);
DISPLAY INVISIBLE (-2650 4750);
FORCEPROP 1 LAST PATH I284
J 0
(-2650 5050);
DISPLAY 0.978723 (-2650 5050);
PAINT WHITE (-2650 5050);
DISPLAY INVISIBLE (-2650 5050);
FORCEPROP 2 LAST CDS_LIB mstr_discrete
J 0
(-2600 4900);
PAINT MONO (-2600 4900);
DISPLAY INVISIBLE (-2600 4900);
FORCEPROP 2 LAST ROOM SB
J 0
(-2600 4900);
PAINT MONO (-2600 4900);
DISPLAY INVISIBLE (-2600 4900);
FORCEPROP 2 LAST SEC_TYPE 0402
J 0
(-2650 5100);
DISPLAY 1.021277 (-2650 5100);
PAINT ORANGE (-2650 5100);
DISPLAY INVISIBLE (-2650 5100);
FORCEPROP 2 LAST SEC 1
J 0
(-2650 5100);
PAINT MONO (-2650 5100);
DISPLAY INVISIBLE (-2650 5100);
FORCEADD OFFPAGE..2
(-1700 4900);
FORCEPROP 2 LAST $XR0 199 
J 0
(-1511 4900);
DISPLAY 0.638298 (-1511 4900);
PAINT MONO (-1511 4900);
FORCEPROP 2 LAST $XR1 119 
J 0
(-1391 4900);
DISPLAY 0.638298 (-1391 4900);
PAINT MONO (-1391 4900);
FORCEPROP 2 LAST $XR2 144 
J 0
(-1271 4900);
DISPLAY 0.638298 (-1271 4900);
PAINT MONO (-1271 4900);
FORCEPROP 1 LAST COMMENT_BODY TRUE
J 0
(-1745 4805);
DISPLAY 1.170213 (-1745 4805);
PAINT GREEN (-1745 4805);
DISPLAY INVISIBLE (-1745 4805);
FORCEPROP 2 LAST CDS_LIB mstr_standard
J 0
(-1700 4900);
PAINT MONO (-1700 4900);
DISPLAY INVISIBLE (-1700 4900);
FORCEPROP 2 LAST BOM_COST SB
J 0
(-1500 4950);
PAINT MONO (-1500 4950);
DISPLAY INVISIBLE (-1500 4950);
FORCEPROP 1 LAST OFFPAGE TRUE
J 0
(-1375 4775);
PAINT GREEN (-1375 4775);
DISPLAY INVISIBLE (-1375 4775);
FORCEPROP 2 LAST PATH I285
J 0
(-1525 4975);
DISPLAY 1.021277 (-1525 4975);
PAINT ORANGE (-1525 4975);
DISPLAY INVISIBLE (-1525 4975);
FORCEADD RES..1
(-4800 950);
FORCEPROP 1 LAST VALUE 1.00K
J 2
(-4900 950);
DISPLAY 0.617021 (-4900 950);
PAINT SKYBLUE (-4900 950);
FORCEPROP 1 LAST WATTAGE 1/16W
J 2
(-4875 900);
DISPLAY 0.617021 (-4875 900);
PAINT SKYBLUE (-4875 900);
FORCEPROP 1 LASTPIN (-4900 950) $PN 1
J 0
(-4888 962);
DISPLAY 0.617021 (-4888 962);
PAINT ORANGE (-4888 962);
FORCEPROP 1 LASTPIN (-4700 950) $PN 2
J 0
(-4738 962);
DISPLAY 0.617021 (-4738 962);
PAINT ORANGE (-4738 962);
FORCEPROP 1 LAST PART_NUMBER G21796-026
J 0
(-4875 900);
DISPLAY 0.617021 (-4875 900);
PAINT BLUE (-4875 900);
FORCEPROP 1 LAST TOLERANCE 1%
J 0
(-4650 900);
DISPLAY 0.617021 (-4650 900);
PAINT SKYBLUE (-4650 900);
FORCEPROP 1 LAST PACK_TYPE 0402
J 0
(-4675 950);
DISPLAY 0.617021 (-4675 950);
PAINT SKYBLUE (-4675 950);
FORCEPROP 1 LAST MATERIAL CHIP
J 0
(-4575 900);
DISPLAY 0.617021 (-4575 900);
PAINT SKYBLUE (-4575 900);
FORCEPROP 1 LAST LOCATION R8C4
J 0
(-4850 1000);
DISPLAY 0.617021 (-4850 1000);
PAINT AQUA (-4850 1000);
FORCEPROP 2 LAST CDS_LIB mstr_discrete
J 0
(-4800 950);
PAINT MONO (-4800 950);
DISPLAY INVISIBLE (-4800 950);
FORCEPROP 2 LAST ROOM SB
J 0
(-4800 950);
PAINT MONO (-4800 950);
DISPLAY INVISIBLE (-4800 950);
FORCEPROP 2 LAST BOM_COST SB_PU_PD
J 0
(-4850 800);
PAINT MONO (-4850 800);
DISPLAY INVISIBLE (-4850 800);
FORCEPROP 2 LAST CDS_LOCATION R8C4
J 0
(-4850 1000);
DISPLAY 0.617021 (-4850 1000);
PAINT AQUA (-4850 1000);
DISPLAY INVISIBLE (-4850 1000);
FORCEPROP 2 LAST SEC 1
J 0
(-4850 1150);
DISPLAY 0.680851 (-4850 1150);
PAINT MONO (-4850 1150);
DISPLAY INVISIBLE (-4850 1150);
FORCEPROP 2 LAST SEC_TYPE 0402
J 0
(-4850 1150);
DISPLAY 1.021277 (-4850 1150);
PAINT ORANGE (-4850 1150);
DISPLAY INVISIBLE (-4850 1150);
FORCEPROP 1 LAST PATH I286
J 0
(-4850 1100);
DISPLAY 0.978723 (-4850 1100);
PAINT WHITE (-4850 1100);
DISPLAY INVISIBLE (-4850 1100);
FORCEADD OFFPAGE..2
(-3925 950);
FORCEPROP 2 LAST $XR0 120 
J 0
(-3736 950);
DISPLAY 0.638298 (-3736 950);
PAINT MONO (-3736 950);
FORCEPROP 2 LAST $XR1 144 
J 0
(-3616 950);
DISPLAY 0.638298 (-3616 950);
PAINT MONO (-3616 950);
FORCEPROP 2 LAST $XR2 119 
J 0
(-3496 950);
DISPLAY 0.638298 (-3496 950);
PAINT MONO (-3496 950);
FORCEPROP 1 LAST COMMENT_BODY TRUE
J 0
(-3970 855);
DISPLAY 1.170213 (-3970 855);
PAINT GREEN (-3970 855);
DISPLAY INVISIBLE (-3970 855);
FORCEPROP 2 LAST CDS_LIB mstr_standard
J 0
(-3925 950);
PAINT MONO (-3925 950);
DISPLAY INVISIBLE (-3925 950);
FORCEPROP 1 LAST OFFPAGE TRUE
J 0
(-3600 825);
PAINT GREEN (-3600 825);
DISPLAY INVISIBLE (-3600 825);
FORCEPROP 2 LAST BOM_COST SB
J 0
(-3725 1000);
PAINT MONO (-3725 1000);
DISPLAY INVISIBLE (-3725 1000);
FORCEPROP 2 LAST PATH I287
J 0
(-3750 1025);
DISPLAY 1.021277 (-3750 1025);
PAINT ORANGE (-3750 1025);
DISPLAY INVISIBLE (-3750 1025);
FORCEADD OFFPAGE..2
(-1650 1025);
FORCEPROP 2 LAST $XR0 120 
J 0
(-1461 1025);
DISPLAY 0.638298 (-1461 1025);
PAINT MONO (-1461 1025);
FORCEPROP 2 LAST $XR1 145 
J 0
(-1341 1025);
DISPLAY 0.638298 (-1341 1025);
PAINT MONO (-1341 1025);
FORCEPROP 2 LAST $XR2 182 
J 0
(-1221 1025);
DISPLAY 0.638298 (-1221 1025);
PAINT MONO (-1221 1025);
FORCEPROP 1 LAST COMMENT_BODY TRUE
J 0
(-1695 930);
DISPLAY 1.170213 (-1695 930);
PAINT GREEN (-1695 930);
DISPLAY INVISIBLE (-1695 930);
FORCEPROP 1 LAST OFFPAGE TRUE
J 0
(-1325 900);
PAINT GREEN (-1325 900);
DISPLAY INVISIBLE (-1325 900);
FORCEPROP 2 LAST CDS_LIB mstr_standard
J 0
(-1650 1025);
PAINT MONO (-1650 1025);
DISPLAY INVISIBLE (-1650 1025);
FORCEPROP 2 LAST BOM_COST SB
J 0
(-1450 1075);
PAINT MONO (-1450 1075);
DISPLAY INVISIBLE (-1450 1075);
FORCEPROP 2 LAST PATH I289
J 0
(-1475 1100);
DISPLAY 1.021277 (-1475 1100);
PAINT ORANGE (-1475 1100);
DISPLAY INVISIBLE (-1475 1100);
FORCEADD OFFPAGE..2
(1375 1075);
FORCEPROP 2 LAST $XR0 121 
J 0
(1564 1075);
DISPLAY 0.638298 (1564 1075);
PAINT MONO (1564 1075);
FORCEPROP 2 LAST $XR1 191 
J 0
(1684 1075);
DISPLAY 0.638298 (1684 1075);
PAINT MONO (1684 1075);
FORCEPROP 1 LAST OFFPAGE TRUE
J 0
(1700 950);
PAINT GREEN (1700 950);
DISPLAY INVISIBLE (1700 950);
FORCEPROP 1 LAST COMMENT_BODY TRUE
J 0
(1330 980);
DISPLAY 1.170213 (1330 980);
PAINT GREEN (1330 980);
DISPLAY INVISIBLE (1330 980);
FORCEPROP 2 LAST CDS_LIB mstr_standard
J 0
(1375 1075);
PAINT MONO (1375 1075);
DISPLAY INVISIBLE (1375 1075);
FORCEPROP 2 LAST PATH I292
J 0
(1700 1125);
DISPLAY 1.021277 (1700 1125);
PAINT ORANGE (1700 1125);
DISPLAY INVISIBLE (1700 1125);
FORCEPROP 2 LAST BOM_COST SB
J 0
(1575 1125);
PAINT MONO (1575 1125);
DISPLAY INVISIBLE (1575 1125);
FORCEADD OFFPAGE..2
(1375 1000);
FORCEPROP 2 LAST $XR0 121 
J 0
(1564 1000);
DISPLAY 0.638298 (1564 1000);
PAINT MONO (1564 1000);
FORCEPROP 2 LAST $XR1 191 
J 0
(1684 1000);
DISPLAY 0.638298 (1684 1000);
PAINT MONO (1684 1000);
FORCEPROP 1 LAST COMMENT_BODY TRUE
J 0
(1330 905);
DISPLAY 1.170213 (1330 905);
PAINT GREEN (1330 905);
DISPLAY INVISIBLE (1330 905);
FORCEPROP 1 LAST OFFPAGE TRUE
J 0
(1700 875);
PAINT GREEN (1700 875);
DISPLAY INVISIBLE (1700 875);
FORCEPROP 2 LAST CDS_LIB mstr_standard
J 0
(1375 1000);
PAINT MONO (1375 1000);
DISPLAY INVISIBLE (1375 1000);
FORCEPROP 2 LAST PATH I293
J 0
(1700 1050);
DISPLAY 1.021277 (1700 1050);
PAINT ORANGE (1700 1050);
DISPLAY INVISIBLE (1700 1050);
FORCEPROP 2 LAST BOM_COST SB
J 0
(1575 1050);
PAINT MONO (1575 1050);
DISPLAY INVISIBLE (1575 1050);
FORCEADD OFFPAGE..2
(1375 1150);
FORCEPROP 2 LAST $XR0 121 
J 0
(1564 1150);
DISPLAY 0.638298 (1564 1150);
PAINT MONO (1564 1150);
FORCEPROP 2 LAST $XR1 191 
J 0
(1684 1150);
DISPLAY 0.638298 (1684 1150);
PAINT MONO (1684 1150);
FORCEPROP 1 LAST COMMENT_BODY TRUE
J 0
(1330 1055);
DISPLAY 1.170213 (1330 1055);
PAINT GREEN (1330 1055);
DISPLAY INVISIBLE (1330 1055);
FORCEPROP 2 LAST CDS_LIB mstr_standard
J 0
(1375 1150);
PAINT MONO (1375 1150);
DISPLAY INVISIBLE (1375 1150);
FORCEPROP 2 LAST PATH I294
J 0
(1700 1200);
DISPLAY 1.021277 (1700 1200);
PAINT ORANGE (1700 1200);
DISPLAY INVISIBLE (1700 1200);
FORCEPROP 1 LAST OFFPAGE TRUE
J 0
(1700 1025);
PAINT GREEN (1700 1025);
DISPLAY INVISIBLE (1700 1025);
FORCEPROP 2 LAST BOM_COST SB
J 0
(1575 1200);
PAINT MONO (1575 1200);
DISPLAY INVISIBLE (1575 1200);
FORCEADD RES..2
(-175 1425);
FORCEPROP 1 LAST PACK_TYPE 0402
J 0
(-135 1250);
DISPLAY 0.617021 (-135 1250);
PAINT SKYBLUE (-135 1250);
FORCEPROP 1 LASTPIN (-175 1325) $PN 2
J 0
(-170 1335);
DISPLAY 0.617021 (-170 1335);
PAINT ORANGE (-170 1335);
FORCEPROP 1 LASTPIN (-175 1525) $PN 1
J 0
(-170 1487);
DISPLAY 0.617021 (-170 1487);
PAINT ORANGE (-170 1487);
FORCEPROP 1 LAST TOLERANCE 1%
J 0
(-130 1450);
DISPLAY 0.617021 (-130 1450);
PAINT SKYBLUE (-130 1450);
FORCEPROP 1 LAST MATERIAL CHIP
J 0
(-135 1350);
DISPLAY 0.617021 (-135 1350);
PAINT SKYBLUE (-135 1350);
FORCEPROP 1 LAST LOCATION R7B6
J 0
(-130 1550);
DISPLAY 0.617021 (-130 1550);
PAINT AQUA (-130 1550);
FORCEPROP 1 LAST WATTAGE 1/16W
J 0
(-135 1400);
DISPLAY 0.617021 (-135 1400);
PAINT SKYBLUE (-135 1400);
FORCEPROP 1 LAST PART_NUMBER G21796-016
J 0
(-135 1300);
DISPLAY 0.617021 (-135 1300);
PAINT BLUE (-135 1300);
FORCEPROP 1 LAST VALUE 10.0K
J 0
(-130 1500);
DISPLAY 0.617021 (-130 1500);
PAINT SKYBLUE (-130 1500);
FORCEPROP 2 LAST CDS_LIB mstr_discrete
J 0
(-175 1425);
PAINT MONO (-175 1425);
DISPLAY INVISIBLE (-175 1425);
FORCEPROP 1 LAST PATH I295
J 0
(-125 1600);
DISPLAY 0.978723 (-125 1600);
PAINT WHITE (-125 1600);
DISPLAY INVISIBLE (-125 1600);
FORCEPROP 2 LAST CDS_LOCATION R7B6
J 0
(-130 1550);
DISPLAY 0.617021 (-130 1550);
PAINT AQUA (-130 1550);
DISPLAY INVISIBLE (-130 1550);
FORCEPROP 2 LAST SEC 1
J 0
(-125 1650);
DISPLAY 0.680851 (-125 1650);
PAINT MONO (-125 1650);
DISPLAY INVISIBLE (-125 1650);
FORCEPROP 2 LAST SEC_TYPE 0402
J 0
(-125 1650);
DISPLAY 1.021277 (-125 1650);
PAINT ORANGE (-125 1650);
DISPLAY INVISIBLE (-125 1650);
FORCEPROP 0 LAST ROOM SB_PU_PD
J 0
(-225 1575);
DISPLAY 1.021277 (-225 1575);
PAINT ORANGE (-225 1575);
DISPLAY INVISIBLE (-225 1575);
FORCEADD RES..2
(-425 1425);
FORCEPROP 1 LAST PACK_TYPE 0402
J 0
(-385 1250);
DISPLAY 0.617021 (-385 1250);
PAINT SKYBLUE (-385 1250);
FORCEPROP 1 LASTPIN (-425 1325) $PN 2
J 0
(-420 1335);
DISPLAY 0.617021 (-420 1335);
PAINT ORANGE (-420 1335);
FORCEPROP 1 LASTPIN (-425 1525) $PN 1
J 0
(-420 1487);
DISPLAY 0.617021 (-420 1487);
PAINT ORANGE (-420 1487);
FORCEPROP 1 LAST MATERIAL CHIP
J 0
(-385 1350);
DISPLAY 0.617021 (-385 1350);
PAINT SKYBLUE (-385 1350);
FORCEPROP 1 LAST TOLERANCE 1%
J 0
(-380 1450);
DISPLAY 0.617021 (-380 1450);
PAINT SKYBLUE (-380 1450);
FORCEPROP 1 LAST WATTAGE 1/16W
J 0
(-385 1400);
DISPLAY 0.617021 (-385 1400);
PAINT SKYBLUE (-385 1400);
FORCEPROP 1 LAST PART_NUMBER G21796-016
J 0
(-385 1300);
DISPLAY 0.617021 (-385 1300);
PAINT BLUE (-385 1300);
FORCEPROP 1 LAST VALUE 10.0K
J 0
(-380 1500);
DISPLAY 0.617021 (-380 1500);
PAINT SKYBLUE (-380 1500);
FORCEPROP 1 LAST LOCATION R7C8
J 0
(-380 1550);
DISPLAY 0.617021 (-380 1550);
PAINT AQUA (-380 1550);
FORCEPROP 2 LAST CDS_LIB mstr_discrete
J 0
(-425 1425);
PAINT MONO (-425 1425);
DISPLAY INVISIBLE (-425 1425);
FORCEPROP 1 LAST PATH I296
J 0
(-375 1600);
DISPLAY 0.978723 (-375 1600);
PAINT WHITE (-375 1600);
DISPLAY INVISIBLE (-375 1600);
FORCEPROP 2 LAST CDS_LOCATION R7C8
J 0
(-380 1550);
DISPLAY 0.617021 (-380 1550);
PAINT AQUA (-380 1550);
DISPLAY INVISIBLE (-380 1550);
FORCEPROP 2 LAST SEC 1
J 0
(-375 1650);
DISPLAY 0.680851 (-375 1650);
PAINT MONO (-375 1650);
DISPLAY INVISIBLE (-375 1650);
FORCEPROP 2 LAST SEC_TYPE 0402
J 0
(-375 1650);
DISPLAY 1.021277 (-375 1650);
PAINT ORANGE (-375 1650);
DISPLAY INVISIBLE (-375 1650);
FORCEPROP 0 LAST ROOM SB_PU_PD
J 0
(-475 1575);
DISPLAY 1.021277 (-475 1575);
PAINT ORANGE (-475 1575);
DISPLAY INVISIBLE (-475 1575);
FORCEADD RES..2
(-650 1425);
FORCEPROP 1 LASTPIN (-650 1525) $PN 1
J 0
(-645 1487);
DISPLAY 0.617021 (-645 1487);
PAINT ORANGE (-645 1487);
FORCEPROP 1 LASTPIN (-650 1325) $PN 2
J 0
(-645 1335);
DISPLAY 0.617021 (-645 1335);
PAINT ORANGE (-645 1335);
FORCEPROP 1 LAST TOLERANCE 1%
J 0
(-605 1450);
DISPLAY 0.617021 (-605 1450);
PAINT SKYBLUE (-605 1450);
FORCEPROP 1 LAST WATTAGE 1/16W
J 0
(-610 1400);
DISPLAY 0.617021 (-610 1400);
PAINT SKYBLUE (-610 1400);
FORCEPROP 1 LAST LOCATION R7C5
J 0
(-605 1550);
DISPLAY 0.617021 (-605 1550);
PAINT AQUA (-605 1550);
FORCEPROP 1 LAST PART_NUMBER G21796-016
J 0
(-610 1300);
DISPLAY 0.617021 (-610 1300);
PAINT BLUE (-610 1300);
FORCEPROP 1 LAST VALUE 10.0K
J 0
(-605 1500);
DISPLAY 0.617021 (-605 1500);
PAINT SKYBLUE (-605 1500);
FORCEPROP 1 LAST PACK_TYPE 0402
J 0
(-610 1250);
DISPLAY 0.617021 (-610 1250);
PAINT SKYBLUE (-610 1250);
FORCEPROP 1 LAST MATERIAL CHIP
J 0
(-610 1350);
DISPLAY 0.617021 (-610 1350);
PAINT SKYBLUE (-610 1350);
FORCEPROP 2 LAST CDS_LIB mstr_discrete
J 0
(-650 1425);
PAINT MONO (-650 1425);
DISPLAY INVISIBLE (-650 1425);
FORCEPROP 0 LAST ROOM SB_PU_PD
J 0
(-700 1575);
DISPLAY 1.021277 (-700 1575);
PAINT ORANGE (-700 1575);
DISPLAY INVISIBLE (-700 1575);
FORCEPROP 2 LAST SEC_TYPE 0402
J 0
(-600 1650);
DISPLAY 1.021277 (-600 1650);
PAINT ORANGE (-600 1650);
DISPLAY INVISIBLE (-600 1650);
FORCEPROP 2 LAST SEC 1
J 0
(-600 1650);
DISPLAY 0.680851 (-600 1650);
PAINT MONO (-600 1650);
DISPLAY INVISIBLE (-600 1650);
FORCEPROP 2 LAST CDS_LOCATION R7C5
J 0
(-605 1550);
DISPLAY 0.617021 (-605 1550);
PAINT AQUA (-605 1550);
DISPLAY INVISIBLE (-605 1550);
FORCEPROP 1 LAST PATH I297
J 0
(-600 1600);
DISPLAY 0.978723 (-600 1600);
PAINT WHITE (-600 1600);
DISPLAY INVISIBLE (-600 1600);
FORCEADD P3V3_STBY..1
(-650 1850);
FORCEPROP 3 LASTPIN (-650 1800) SIG_NAME P3V3_STBY\g
J 0
(-640 1810);
DISPLAY 0.659574 (-640 1810);
PAINT MONO (-640 1810);
DISPLAY INVISIBLE (-640 1810);
FORCEPROP 1 LAST HDL_POWER P3V3_STBY
J 0
(-950 1725);
DISPLAY 0.872340 (-950 1725);
PAINT ORANGE (-950 1725);
DISPLAY INVISIBLE (-950 1725);
FORCEPROP 1 LAST VOLTAGE 3.3V
J 0
(-695 1807);
DISPLAY 0.340426 (-695 1807);
PAINT SKYBLUE (-695 1807);
DISPLAY INVISIBLE (-695 1807);
FORCEPROP 1 LAST SIZE 1B
J 0
(-605 1872);
DISPLAY 0.340426 (-605 1872);
PAINT GREEN (-605 1872);
DISPLAY INVISIBLE (-605 1872);
FORCEPROP 2 LAST CDS_LIB mstr_symbols
J 0
(-650 1850);
PAINT MONO (-650 1850);
DISPLAY INVISIBLE (-650 1850);
FORCEPROP 1 LAST BODY_TYPE PLUMBING
J 0
(-695 1807);
DISPLAY 0.340426 (-695 1807);
PAINT GREEN (-695 1807);
DISPLAY INVISIBLE (-695 1807);
FORCEPROP 1 LAST PATH I298
J 0
(-605 1852);
DISPLAY 0.340426 (-605 1852);
PAINT GREEN (-605 1852);
DISPLAY INVISIBLE (-605 1852);
FORCEADD OFFPAGE..2
(-1575 1800);
FORCEPROP 2 LAST $XR0 120 
J 0
(-1386 1800);
DISPLAY 0.638298 (-1386 1800);
PAINT MONO (-1386 1800);
FORCEPROP 2 LAST $XR1 146 
J 0
(-1266 1800);
DISPLAY 0.638298 (-1266 1800);
PAINT MONO (-1266 1800);
FORCEPROP 2 LAST $XR2 151 
J 0
(-1146 1800);
DISPLAY 0.638298 (-1146 1800);
PAINT MONO (-1146 1800);
FORCEPROP 2 LAST $XR3 175 
J 0
(-1146 1800);
DISPLAY 0.638298 (-1146 1800);
PAINT MONO (-1146 1800);
FORCEPROP 1 LAST COMMENT_BODY TRUE
J 0
(-1620 1705);
DISPLAY 1.170213 (-1620 1705);
PAINT GREEN (-1620 1705);
DISPLAY INVISIBLE (-1620 1705);
FORCEPROP 2 LAST CDS_LIB mstr_standard
J 0
(-1575 1800);
PAINT MONO (-1575 1800);
DISPLAY INVISIBLE (-1575 1800);
FORCEPROP 2 LAST PATH I299
J 0
(-1400 1875);
DISPLAY 1.021277 (-1400 1875);
PAINT ORANGE (-1400 1875);
DISPLAY INVISIBLE (-1400 1875);
FORCEPROP 1 LAST OFFPAGE TRUE
J 0
(-1250 1675);
PAINT GREEN (-1250 1675);
DISPLAY INVISIBLE (-1250 1675);
FORCEPROP 2 LAST BOM_COST SB
J 0
(-1250 1850);
PAINT MONO (-1250 1850);
DISPLAY INVISIBLE (-1250 1850);
FORCEADD P3V3_STBY..1
(-2800 2050);
FORCEPROP 3 LASTPIN (-2800 2000) SIG_NAME P3V3_STBY\g
J 0
(-2790 2010);
DISPLAY 0.659574 (-2790 2010);
PAINT MONO (-2790 2010);
DISPLAY INVISIBLE (-2790 2010);
FORCEPROP 1 LAST HDL_POWER P3V3_STBY
J 0
(-3100 1925);
DISPLAY 0.872340 (-3100 1925);
PAINT ORANGE (-3100 1925);
DISPLAY INVISIBLE (-3100 1925);
FORCEPROP 1 LAST VOLTAGE 3.3V
J 0
(-2845 2007);
DISPLAY 0.340426 (-2845 2007);
PAINT SKYBLUE (-2845 2007);
DISPLAY INVISIBLE (-2845 2007);
FORCEPROP 1 LAST BODY_TYPE PLUMBING
J 0
(-2845 2007);
DISPLAY 0.340426 (-2845 2007);
PAINT GREEN (-2845 2007);
DISPLAY INVISIBLE (-2845 2007);
FORCEPROP 1 LAST PATH I300
J 0
(-2755 2052);
DISPLAY 0.340426 (-2755 2052);
PAINT GREEN (-2755 2052);
DISPLAY INVISIBLE (-2755 2052);
FORCEPROP 1 LAST SIZE 1B
J 0
(-2755 2072);
DISPLAY 0.340426 (-2755 2072);
PAINT GREEN (-2755 2072);
DISPLAY INVISIBLE (-2755 2072);
FORCEPROP 2 LAST CDS_LIB mstr_symbols
J 0
(-2800 2050);
PAINT MONO (-2800 2050);
DISPLAY INVISIBLE (-2800 2050);
FORCEADD RES..1
(-2475 1800);
FORCEPROP 1 LAST WATTAGE 1/16W
J 2
(-2500 1650);
DISPLAY 0.617021 (-2500 1650);
PAINT SKYBLUE (-2500 1650);
FORCEPROP 1 LAST VALUE 4.75K
J 2
(-2500 1700);
DISPLAY 0.617021 (-2500 1700);
PAINT SKYBLUE (-2500 1700);
FORCEPROP 1 LASTPIN (-2575 1800) $PN 1
J 0
(-2563 1812);
DISPLAY 0.617021 (-2563 1812);
PAINT ORANGE (-2563 1812);
FORCEPROP 1 LAST TOLERANCE 1%
J 0
(-2475 1700);
DISPLAY 0.617021 (-2475 1700);
PAINT SKYBLUE (-2475 1700);
FORCEPROP 1 LAST MATERIAL CHIP
J 0
(-2475 1650);
DISPLAY 0.617021 (-2475 1650);
PAINT SKYBLUE (-2475 1650);
FORCEPROP 1 LAST LOCATION R8D14
J 0
(-2525 1850);
DISPLAY 0.617021 (-2525 1850);
PAINT AQUA (-2525 1850);
FORCEPROP 1 LASTPIN (-2375 1800) $PN 2
J 0
(-2413 1812);
DISPLAY 0.617021 (-2413 1812);
PAINT ORANGE (-2413 1812);
FORCEPROP 1 LAST PART_NUMBER G21796-072
J 0
(-2525 1900);
DISPLAY 0.617021 (-2525 1900);
PAINT BLUE (-2525 1900);
FORCEPROP 1 LAST PACK_TYPE 0402
J 0
(-2225 1650);
DISPLAY 0.617021 (-2225 1650);
PAINT SKYBLUE (-2225 1650);
FORCEPROP 2 LAST BOM_COST SB
J 0
(-2525 1650);
PAINT MONO (-2525 1650);
DISPLAY INVISIBLE (-2525 1650);
FORCEPROP 2 LAST CDS_LIB mstr_discrete
J 0
(-2475 1800);
PAINT ORANGE (-2475 1800);
DISPLAY INVISIBLE (-2475 1800);
FORCEPROP 2 LAST ROOM SB
J 0
(-2475 1800);
PAINT MONO (-2475 1800);
DISPLAY INVISIBLE (-2475 1800);
FORCEPROP 2 LAST SEC_TYPE 0402
J 0
(-2525 2000);
DISPLAY 1.021277 (-2525 2000);
PAINT ORANGE (-2525 2000);
DISPLAY INVISIBLE (-2525 2000);
FORCEPROP 2 LAST SEC 1
J 0
(-2525 2000);
DISPLAY 0.680851 (-2525 2000);
PAINT MONO (-2525 2000);
DISPLAY INVISIBLE (-2525 2000);
FORCEPROP 1 LAST PATH I301
J 0
(-2525 1950);
DISPLAY 0.978723 (-2525 1950);
PAINT WHITE (-2525 1950);
DISPLAY INVISIBLE (-2525 1950);
FORCEPROP 2 LAST CDS_LOCATION R8D14
J 0
(-2525 1850);
DISPLAY 0.617021 (-2525 1850);
PAINT AQUA (-2525 1850);
DISPLAY INVISIBLE (-2525 1850);
FORCEADD P3V3_STBY..1
(-4950 5225);
FORCEPROP 3 LASTPIN (-4950 5175) SIG_NAME P3V3_STBY\g
J 0
(-4940 5185);
DISPLAY 0.659574 (-4940 5185);
PAINT MONO (-4940 5185);
DISPLAY INVISIBLE (-4940 5185);
FORCEPROP 1 LAST HDL_POWER P3V3_STBY
J 0
(-5250 5100);
DISPLAY 0.872340 (-5250 5100);
PAINT ORANGE (-5250 5100);
DISPLAY INVISIBLE (-5250 5100);
FORCEPROP 1 LAST PATH I302
J 0
(-4905 5227);
DISPLAY 0.340426 (-4905 5227);
PAINT GREEN (-4905 5227);
DISPLAY INVISIBLE (-4905 5227);
FORCEPROP 1 LAST BODY_TYPE PLUMBING
J 0
(-4995 5182);
DISPLAY 0.340426 (-4995 5182);
PAINT GREEN (-4995 5182);
DISPLAY INVISIBLE (-4995 5182);
FORCEPROP 2 LAST CDS_LIB mstr_symbols
J 0
(-4950 5225);
PAINT MONO (-4950 5225);
DISPLAY INVISIBLE (-4950 5225);
FORCEPROP 1 LAST SIZE 1B
J 0
(-4905 5247);
DISPLAY 0.340426 (-4905 5247);
PAINT GREEN (-4905 5247);
DISPLAY INVISIBLE (-4905 5247);
FORCEPROP 1 LAST VOLTAGE 3.3V
J 0
(-4995 5182);
DISPLAY 0.340426 (-4995 5182);
PAINT SKYBLUE (-4995 5182);
DISPLAY INVISIBLE (-4995 5182);
FORCEADD RES..1
(-4675 2400);
FORCEPROP 1 LAST WATTAGE 1/16W
J 2
(-4750 2350);
DISPLAY 0.617021 (-4750 2350);
PAINT SKYBLUE (-4750 2350);
FORCEPROP 1 LASTPIN (-4775 2400) $PN 1
J 0
(-4763 2412);
DISPLAY 0.617021 (-4763 2412);
PAINT ORANGE (-4763 2412);
FORCEPROP 1 LAST PACK_TYPE 0402
J 0
(-4850 2425);
DISPLAY 0.617021 (-4850 2425);
PAINT SKYBLUE (-4850 2425);
FORCEPROP 1 LAST LOCATION R8C6
J 0
(-4725 2450);
DISPLAY 0.617021 (-4725 2450);
PAINT AQUA (-4725 2450);
FORCEPROP 1 LAST VALUE 4.75K
J 2
(-4500 2425);
DISPLAY 0.617021 (-4500 2425);
PAINT SKYBLUE (-4500 2425);
FORCEPROP 1 LASTPIN (-4575 2400) $PN 2
J 0
(-4613 2412);
DISPLAY 0.617021 (-4613 2412);
PAINT ORANGE (-4613 2412);
FORCEPROP 1 LAST PART_NUMBER G21796-072
J 0
(-4475 2425);
DISPLAY 0.617021 (-4475 2425);
PAINT BLUE (-4475 2425);
FORCEPROP 1 LAST TOLERANCE 1%
J 0
(-4575 2350);
DISPLAY 0.617021 (-4575 2350);
PAINT SKYBLUE (-4575 2350);
FORCEPROP 1 LAST MATERIAL CHIP
J 0
(-4500 2350);
DISPLAY 0.617021 (-4500 2350);
PAINT SKYBLUE (-4500 2350);
FORCEPROP 2 LAST CDS_LOCATION R8C6
J 0
(-4725 2450);
DISPLAY 0.617021 (-4725 2450);
PAINT AQUA (-4725 2450);
DISPLAY INVISIBLE (-4725 2450);
FORCEPROP 2 LAST CDS_LIB mstr_discrete
J 0
(-4675 2400);
PAINT MONO (-4675 2400);
DISPLAY INVISIBLE (-4675 2400);
FORCEPROP 2 LAST ROOM SB_PU_PD
J 0
(-4725 2500);
DISPLAY 1.021277 (-4725 2500);
PAINT ORANGE (-4725 2500);
DISPLAY INVISIBLE (-4725 2500);
FORCEPROP 1 LAST PATH I303
J 0
(-4725 2550);
DISPLAY 0.978723 (-4725 2550);
PAINT WHITE (-4725 2550);
DISPLAY INVISIBLE (-4725 2550);
FORCEPROP 2 LAST SEC 1
J 0
(-4725 2600);
DISPLAY 0.680851 (-4725 2600);
PAINT MONO (-4725 2600);
DISPLAY INVISIBLE (-4725 2600);
FORCEPROP 2 LAST SEC_TYPE 0402
J 0
(-4725 2600);
DISPLAY 1.021277 (-4725 2600);
PAINT ORANGE (-4725 2600);
DISPLAY INVISIBLE (-4725 2600);
FORCEADD RES..1
(-4800 1825);
FORCEPROP 1 LAST WATTAGE 1/16W
J 2
(-4875 1775);
DISPLAY 0.617021 (-4875 1775);
PAINT SKYBLUE (-4875 1775);
FORCEPROP 1 LAST VALUE 4.75K
J 2
(-4900 1825);
DISPLAY 0.617021 (-4900 1825);
PAINT SKYBLUE (-4900 1825);
FORCEPROP 1 LASTPIN (-4900 1825) $PN 1
J 0
(-4888 1837);
DISPLAY 0.617021 (-4888 1837);
PAINT ORANGE (-4888 1837);
FORCEPROP 1 LAST LOCATION R8C2
J 0
(-4850 1875);
DISPLAY 0.617021 (-4850 1875);
PAINT AQUA (-4850 1875);
FORCEPROP 1 LASTPIN (-4700 1825) $PN 2
J 0
(-4738 1837);
DISPLAY 0.617021 (-4738 1837);
PAINT ORANGE (-4738 1837);
FORCEPROP 1 LAST PART_NUMBER G21796-072
J 0
(-4875 1775);
DISPLAY 0.617021 (-4875 1775);
PAINT BLUE (-4875 1775);
FORCEPROP 1 LAST TOLERANCE 1%
J 0
(-4650 1775);
DISPLAY 0.617021 (-4650 1775);
PAINT SKYBLUE (-4650 1775);
FORCEPROP 1 LAST PACK_TYPE 0402
J 0
(-4675 1825);
DISPLAY 0.617021 (-4675 1825);
PAINT SKYBLUE (-4675 1825);
FORCEPROP 1 LAST MATERIAL CHIP
J 0
(-4575 1775);
DISPLAY 0.617021 (-4575 1775);
PAINT SKYBLUE (-4575 1775);
FORCEPROP 2 LAST CDS_LOCATION R8C2
J 0
(-4850 1875);
DISPLAY 0.617021 (-4850 1875);
PAINT AQUA (-4850 1875);
DISPLAY INVISIBLE (-4850 1875);
FORCEPROP 2 LAST CDS_LIB mstr_discrete
J 0
(-4800 1825);
PAINT MONO (-4800 1825);
DISPLAY INVISIBLE (-4800 1825);
FORCEPROP 1 LAST PATH I304
J 0
(-4850 1975);
DISPLAY 0.978723 (-4850 1975);
PAINT WHITE (-4850 1975);
DISPLAY INVISIBLE (-4850 1975);
FORCEPROP 2 LAST ROOM SB_PU_PD
J 0
(-4850 1925);
DISPLAY 1.021277 (-4850 1925);
PAINT ORANGE (-4850 1925);
DISPLAY INVISIBLE (-4850 1925);
FORCEPROP 2 LAST SEC_TYPE 0402
J 0
(-4850 2025);
DISPLAY 1.021277 (-4850 2025);
PAINT ORANGE (-4850 2025);
DISPLAY INVISIBLE (-4850 2025);
FORCEPROP 2 LAST SEC 1
J 0
(-4850 2025);
DISPLAY 0.680851 (-4850 2025);
PAINT MONO (-4850 2025);
DISPLAY INVISIBLE (-4850 2025);
FORCEADD RES..1
(-4700 3700);
FORCEPROP 1 LAST WATTAGE 1/16W
J 2
(-4775 3650);
DISPLAY 0.617021 (-4775 3650);
PAINT SKYBLUE (-4775 3650);
FORCEPROP 1 LAST PACK_TYPE 0402
J 0
(-4875 3725);
DISPLAY 0.617021 (-4875 3725);
PAINT SKYBLUE (-4875 3725);
FORCEPROP 1 LASTPIN (-4800 3700) $PN 1
J 0
(-4788 3712);
DISPLAY 0.617021 (-4788 3712);
PAINT ORANGE (-4788 3712);
FORCEPROP 1 LAST LOCATION R7D6
J 0
(-4750 3750);
DISPLAY 0.617021 (-4750 3750);
PAINT AQUA (-4750 3750);
FORCEPROP 1 LASTPIN (-4600 3700) $PN 2
J 0
(-4638 3712);
DISPLAY 0.617021 (-4638 3712);
PAINT ORANGE (-4638 3712);
FORCEPROP 1 LAST PART_NUMBER G21796-072
J 0
(-4775 3625);
DISPLAY 0.617021 (-4775 3625);
PAINT BLUE (-4775 3625);
FORCEPROP 1 LAST VALUE 4.75K
J 2
(-4525 3725);
DISPLAY 0.617021 (-4525 3725);
PAINT SKYBLUE (-4525 3725);
FORCEPROP 1 LAST TOLERANCE 1%
J 0
(-4600 3650);
DISPLAY 0.617021 (-4600 3650);
PAINT SKYBLUE (-4600 3650);
FORCEPROP 1 LAST MATERIAL CHIP
J 0
(-4525 3650);
DISPLAY 0.617021 (-4525 3650);
PAINT SKYBLUE (-4525 3650);
FORCEPROP 2 LAST CDS_LOCATION R7D6
J 0
(-4750 3750);
DISPLAY 0.617021 (-4750 3750);
PAINT AQUA (-4750 3750);
DISPLAY INVISIBLE (-4750 3750);
FORCEPROP 2 LAST CDS_LIB mstr_discrete
J 0
(-4700 3700);
PAINT MONO (-4700 3700);
DISPLAY INVISIBLE (-4700 3700);
FORCEPROP 2 LAST ROOM SB_PU_PD
J 0
(-4750 3800);
DISPLAY 1.021277 (-4750 3800);
PAINT ORANGE (-4750 3800);
DISPLAY INVISIBLE (-4750 3800);
FORCEPROP 1 LAST PATH I306
J 0
(-4750 3850);
DISPLAY 0.978723 (-4750 3850);
PAINT WHITE (-4750 3850);
DISPLAY INVISIBLE (-4750 3850);
FORCEPROP 2 LAST SEC 1
J 0
(-4750 3900);
DISPLAY 0.680851 (-4750 3900);
PAINT MONO (-4750 3900);
DISPLAY INVISIBLE (-4750 3900);
FORCEPROP 2 LAST SEC_TYPE 0402
J 0
(-4750 3900);
DISPLAY 1.021277 (-4750 3900);
PAINT ORANGE (-4750 3900);
DISPLAY INVISIBLE (-4750 3900);
FORCEADD RES..1
(-4800 1650);
FORCEPROP 1 LAST VALUE 4.75K
J 2
(-4900 1650);
DISPLAY 0.617021 (-4900 1650);
PAINT SKYBLUE (-4900 1650);
FORCEPROP 1 LAST WATTAGE 1/16W
J 2
(-4875 1600);
DISPLAY 0.617021 (-4875 1600);
PAINT SKYBLUE (-4875 1600);
FORCEPROP 1 LASTPIN (-4900 1650) $PN 1
J 0
(-4888 1662);
DISPLAY 0.617021 (-4888 1662);
PAINT ORANGE (-4888 1662);
FORCEPROP 1 LASTPIN (-4700 1650) $PN 2
J 0
(-4738 1662);
DISPLAY 0.617021 (-4738 1662);
PAINT ORANGE (-4738 1662);
FORCEPROP 1 LAST LOCATION R8B31
J 0
(-4850 1700);
DISPLAY 0.617021 (-4850 1700);
PAINT AQUA (-4850 1700);
FORCEPROP 1 LAST PART_NUMBER G21796-072
J 0
(-4875 1600);
DISPLAY 0.617021 (-4875 1600);
PAINT BLUE (-4875 1600);
FORCEPROP 1 LAST TOLERANCE 1%
J 0
(-4650 1600);
DISPLAY 0.617021 (-4650 1600);
PAINT SKYBLUE (-4650 1600);
FORCEPROP 1 LAST PACK_TYPE 0402
J 0
(-4675 1650);
DISPLAY 0.617021 (-4675 1650);
PAINT SKYBLUE (-4675 1650);
FORCEPROP 1 LAST MATERIAL CHIP
J 0
(-4575 1600);
DISPLAY 0.617021 (-4575 1600);
PAINT SKYBLUE (-4575 1600);
FORCEPROP 2 LAST CDS_LOCATION R8B31
J 0
(-4850 1700);
DISPLAY 0.617021 (-4850 1700);
PAINT AQUA (-4850 1700);
DISPLAY INVISIBLE (-4850 1700);
FORCEPROP 2 LAST CDS_LIB mstr_discrete
J 0
(-4800 1650);
PAINT MONO (-4800 1650);
DISPLAY INVISIBLE (-4800 1650);
FORCEPROP 2 LAST ROOM SB_PU_PD
J 0
(-4850 1750);
DISPLAY 1.021277 (-4850 1750);
PAINT ORANGE (-4850 1750);
DISPLAY INVISIBLE (-4850 1750);
FORCEPROP 1 LAST PATH I307
J 0
(-4850 1800);
DISPLAY 0.978723 (-4850 1800);
PAINT WHITE (-4850 1800);
DISPLAY INVISIBLE (-4850 1800);
FORCEPROP 2 LAST SEC 1
J 0
(-4850 1850);
DISPLAY 0.680851 (-4850 1850);
PAINT MONO (-4850 1850);
DISPLAY INVISIBLE (-4850 1850);
FORCEPROP 2 LAST SEC_TYPE 0402
J 0
(-4850 1850);
DISPLAY 1.021277 (-4850 1850);
PAINT ORANGE (-4850 1850);
DISPLAY INVISIBLE (-4850 1850);
FORCEADD RES..1
(-2475 1025);
FORCEPROP 1 LAST WATTAGE 1/16W
J 2
(-2550 975);
DISPLAY 0.617021 (-2550 975);
PAINT SKYBLUE (-2550 975);
FORCEPROP 1 LAST TOLERANCE 1%
J 0
(-2375 975);
DISPLAY 0.617021 (-2375 975);
PAINT SKYBLUE (-2375 975);
FORCEPROP 1 LAST PART_NUMBER G21796-072
J 0
(-2550 950);
DISPLAY 0.617021 (-2550 950);
PAINT BLUE (-2550 950);
FORCEPROP 1 LAST MATERIAL CHIP
J 0
(-2300 975);
DISPLAY 0.617021 (-2300 975);
PAINT SKYBLUE (-2300 975);
FORCEPROP 1 LASTPIN (-2575 1025) $PN 1
J 0
(-2563 1037);
DISPLAY 0.617021 (-2563 1037);
PAINT ORANGE (-2563 1037);
FORCEPROP 1 LAST PACK_TYPE 0402
J 0
(-2650 1050);
DISPLAY 0.617021 (-2650 1050);
PAINT SKYBLUE (-2650 1050);
FORCEPROP 1 LAST LOCATION R2N7
J 0
(-2525 1075);
DISPLAY 0.617021 (-2525 1075);
PAINT AQUA (-2525 1075);
FORCEPROP 1 LASTPIN (-2375 1025) $PN 2
J 0
(-2413 1037);
DISPLAY 0.617021 (-2413 1037);
PAINT ORANGE (-2413 1037);
FORCEPROP 1 LAST VALUE 4.75K
J 2
(-2300 1050);
DISPLAY 0.617021 (-2300 1050);
PAINT SKYBLUE (-2300 1050);
FORCEPROP 1 LAST PATH I309
J 0
(-2525 1175);
DISPLAY 0.978723 (-2525 1175);
PAINT WHITE (-2525 1175);
DISPLAY INVISIBLE (-2525 1175);
FORCEPROP 2 LAST CDS_LOCATION R2N7
J 0
(-2525 1075);
DISPLAY 0.617021 (-2525 1075);
PAINT AQUA (-2525 1075);
DISPLAY INVISIBLE (-2525 1075);
FORCEPROP 2 LAST SEC 1
J 0
(-2525 1225);
DISPLAY 0.680851 (-2525 1225);
PAINT MONO (-2525 1225);
DISPLAY INVISIBLE (-2525 1225);
FORCEPROP 2 LAST CDS_LIB mstr_discrete
J 0
(-2475 1025);
PAINT MONO (-2475 1025);
DISPLAY INVISIBLE (-2475 1025);
FORCEPROP 2 LAST SEC_TYPE 0402
J 0
(-2525 1225);
DISPLAY 1.021277 (-2525 1225);
PAINT ORANGE (-2525 1225);
DISPLAY INVISIBLE (-2525 1225);
FORCEPROP 2 LAST ROOM SB_PU_PD
J 0
(-2525 1125);
DISPLAY 1.021277 (-2525 1125);
PAINT ORANGE (-2525 1125);
DISPLAY INVISIBLE (-2525 1125);
FORCEADD OFFPAGE..2
(625 5100);
FORCEPROP 2 LAST $XR0 108 
J 0
(814 5100);
DISPLAY 0.638298 (814 5100);
PAINT MONO (814 5100);
FORCEPROP 2 LAST $XR1 121 
J 0
(934 5100);
DISPLAY 0.638298 (934 5100);
PAINT MONO (934 5100);
FORCEPROP 1 LAST COMMENT_BODY TRUE
J 0
(580 5005);
DISPLAY 1.170213 (580 5005);
PAINT GREEN (580 5005);
DISPLAY INVISIBLE (580 5005);
FORCEPROP 1 LAST OFFPAGE TRUE
J 0
(950 4975);
PAINT GREEN (950 4975);
DISPLAY INVISIBLE (950 4975);
FORCEPROP 2 LAST CDS_LIB mstr_standard
J 0
(625 5100);
PAINT MONO (625 5100);
DISPLAY INVISIBLE (625 5100);
FORCEPROP 2 LAST PATH I311
J 0
(800 5175);
DISPLAY 1.021277 (800 5175);
PAINT ORANGE (800 5175);
DISPLAY INVISIBLE (800 5175);
FORCEPROP 2 LAST BOM_COST SB
J 0
(825 5150);
PAINT MONO (825 5150);
DISPLAY INVISIBLE (825 5150);
FORCEADD OFFPAGE..2
(625 4875);
FORCEPROP 2 LAST $XR0 108 
J 0
(814 4875);
DISPLAY 0.638298 (814 4875);
PAINT MONO (814 4875);
FORCEPROP 2 LAST $XR1 121 
J 0
(934 4875);
DISPLAY 0.638298 (934 4875);
PAINT MONO (934 4875);
FORCEPROP 1 LAST COMMENT_BODY TRUE
J 0
(580 4780);
DISPLAY 1.170213 (580 4780);
PAINT GREEN (580 4780);
DISPLAY INVISIBLE (580 4780);
FORCEPROP 2 LAST CDS_LIB mstr_standard
J 0
(625 4875);
PAINT MONO (625 4875);
DISPLAY INVISIBLE (625 4875);
FORCEPROP 2 LAST PATH I312
J 0
(800 4950);
DISPLAY 1.021277 (800 4950);
PAINT ORANGE (800 4950);
DISPLAY INVISIBLE (800 4950);
FORCEPROP 1 LAST OFFPAGE TRUE
J 0
(950 4750);
PAINT GREEN (950 4750);
DISPLAY INVISIBLE (950 4750);
FORCEPROP 2 LAST BOM_COST SB
J 0
(825 4925);
PAINT MONO (825 4925);
DISPLAY INVISIBLE (825 4925);
FORCEADD OFFPAGE..2
(625 4650);
FORCEPROP 2 LAST $XR0 108 
J 0
(814 4650);
DISPLAY 0.638298 (814 4650);
PAINT MONO (814 4650);
FORCEPROP 2 LAST $XR1 121 
J 0
(934 4650);
DISPLAY 0.638298 (934 4650);
PAINT MONO (934 4650);
FORCEPROP 1 LAST COMMENT_BODY TRUE
J 0
(580 4555);
DISPLAY 1.170213 (580 4555);
PAINT GREEN (580 4555);
DISPLAY INVISIBLE (580 4555);
FORCEPROP 1 LAST OFFPAGE TRUE
J 0
(950 4525);
PAINT GREEN (950 4525);
DISPLAY INVISIBLE (950 4525);
FORCEPROP 2 LAST CDS_LIB mstr_standard
J 0
(625 4650);
PAINT MONO (625 4650);
DISPLAY INVISIBLE (625 4650);
FORCEPROP 2 LAST PATH I313
J 0
(800 4725);
DISPLAY 1.021277 (800 4725);
PAINT ORANGE (800 4725);
DISPLAY INVISIBLE (800 4725);
FORCEPROP 2 LAST BOM_COST SB
J 0
(825 4700);
PAINT MONO (825 4700);
DISPLAY INVISIBLE (825 4700);
FORCEADD OFFPAGE..2
(625 4400);
FORCEPROP 2 LAST $XR0 108 
J 0
(814 4400);
DISPLAY 0.638298 (814 4400);
PAINT MONO (814 4400);
FORCEPROP 2 LAST $XR1 121 
J 0
(934 4400);
DISPLAY 0.638298 (934 4400);
PAINT MONO (934 4400);
FORCEPROP 1 LAST COMMENT_BODY TRUE
J 0
(580 4305);
DISPLAY 1.170213 (580 4305);
PAINT GREEN (580 4305);
DISPLAY INVISIBLE (580 4305);
FORCEPROP 2 LAST CDS_LIB mstr_standard
J 0
(625 4400);
PAINT MONO (625 4400);
DISPLAY INVISIBLE (625 4400);
FORCEPROP 2 LAST PATH I314
J 0
(800 4475);
DISPLAY 1.021277 (800 4475);
PAINT ORANGE (800 4475);
DISPLAY INVISIBLE (800 4475);
FORCEPROP 1 LAST OFFPAGE TRUE
J 0
(950 4275);
PAINT GREEN (950 4275);
DISPLAY INVISIBLE (950 4275);
FORCEPROP 2 LAST BOM_COST SB
J 0
(825 4450);
PAINT MONO (825 4450);
DISPLAY INVISIBLE (825 4450);
FORCEADD RES..1
(-400 5100);
FORCEPROP 1 LAST VALUE 1.00K
J 2
(-425 5050);
DISPLAY 0.617021 (-425 5050);
PAINT SKYBLUE (-425 5050);
FORCEPROP 1 LAST TOLERANCE 1%
J 0
(-370 5050);
DISPLAY 0.617021 (-370 5050);
PAINT SKYBLUE (-370 5050);
FORCEPROP 1 LAST PACK_TYPE 0402
J 0
(-290 5060);
DISPLAY 0.617021 (-290 5060);
PAINT SKYBLUE (-290 5060);
FORCEPROP 1 LAST MATERIAL CHIP
J 0
(-185 5060);
DISPLAY 0.617021 (-185 5060);
PAINT SKYBLUE (-185 5060);
FORCEPROP 1 LASTPIN (-300 5100) $PN 2
J 0
(-338 5112);
DISPLAY 0.617021 (-338 5112);
PAINT ORANGE (-338 5112);
FORCEPROP 1 LASTPIN (-500 5100) $PN 1
J 0
(-488 5112);
DISPLAY 0.617021 (-488 5112);
PAINT ORANGE (-488 5112);
FORCEPROP 1 LAST LOCATION R3P7
J 0
(-425 5150);
DISPLAY 0.617021 (-425 5150);
PAINT AQUA (-425 5150);
FORCEPROP 1 LAST PART_NUMBER G21796-026
J 0
(-300 5125);
DISPLAY 0.617021 (-300 5125);
PAINT BLUE (-300 5125);
FORCEPROP 1 LAST WATTAGE 1/16W
J 2
(80 5060);
DISPLAY 0.617021 (80 5060);
PAINT SKYBLUE (80 5060);
FORCEPROP 2 LAST BOM_COST SB
J 0
(-450 4950);
PAINT MONO (-450 4950);
DISPLAY INVISIBLE (-450 4950);
FORCEPROP 2 LAST ROOM SB
J 0
(-400 5100);
PAINT MONO (-400 5100);
DISPLAY INVISIBLE (-400 5100);
FORCEPROP 2 LAST CDS_LIB mstr_discrete
J 0
(-400 5100);
PAINT MONO (-400 5100);
DISPLAY INVISIBLE (-400 5100);
FORCEPROP 2 LAST CDS_LOCATION R3P7
J 0
(-425 5150);
DISPLAY 0.617021 (-425 5150);
PAINT AQUA (-425 5150);
DISPLAY INVISIBLE (-425 5150);
FORCEPROP 2 LAST SEC 1
J 0
(-450 5300);
DISPLAY 0.680851 (-450 5300);
PAINT MONO (-450 5300);
DISPLAY INVISIBLE (-450 5300);
FORCEPROP 2 LAST SEC_TYPE 0402
J 0
(-450 5300);
DISPLAY 1.021277 (-450 5300);
PAINT ORANGE (-450 5300);
DISPLAY INVISIBLE (-450 5300);
FORCEPROP 1 LAST PATH I315
J 0
(-450 5250);
DISPLAY 0.978723 (-450 5250);
PAINT WHITE (-450 5250);
DISPLAY INVISIBLE (-450 5250);
FORCEADD RES..1
(-400 4875);
FORCEPROP 1 LAST VALUE 1.00K
J 2
(-425 4825);
DISPLAY 0.617021 (-425 4825);
PAINT SKYBLUE (-425 4825);
FORCEPROP 1 LAST TOLERANCE 1%
J 0
(-370 4825);
DISPLAY 0.617021 (-370 4825);
PAINT SKYBLUE (-370 4825);
FORCEPROP 1 LASTPIN (-500 4875) $PN 1
J 0
(-488 4887);
DISPLAY 0.617021 (-488 4887);
PAINT ORANGE (-488 4887);
FORCEPROP 1 LAST LOCATION R3P5
J 0
(-425 4925);
DISPLAY 0.617021 (-425 4925);
PAINT AQUA (-425 4925);
FORCEPROP 1 LASTPIN (-300 4875) $PN 2
J 0
(-338 4887);
DISPLAY 0.617021 (-338 4887);
PAINT ORANGE (-338 4887);
FORCEPROP 1 LAST PART_NUMBER G21796-026
J 0
(-300 4900);
DISPLAY 0.617021 (-300 4900);
PAINT BLUE (-300 4900);
FORCEPROP 1 LAST PACK_TYPE 0402
J 0
(-290 4835);
DISPLAY 0.617021 (-290 4835);
PAINT SKYBLUE (-290 4835);
FORCEPROP 1 LAST MATERIAL CHIP
J 0
(-185 4835);
DISPLAY 0.617021 (-185 4835);
PAINT SKYBLUE (-185 4835);
FORCEPROP 1 LAST WATTAGE 1/16W
J 2
(80 4835);
DISPLAY 0.617021 (80 4835);
PAINT SKYBLUE (80 4835);
FORCEPROP 2 LAST BOM_COST SB
J 0
(-450 4725);
PAINT MONO (-450 4725);
DISPLAY INVISIBLE (-450 4725);
FORCEPROP 2 LAST ROOM SB
J 0
(-400 4875);
PAINT MONO (-400 4875);
DISPLAY INVISIBLE (-400 4875);
FORCEPROP 2 LAST CDS_LOCATION R3P5
J 0
(-425 4925);
DISPLAY 0.617021 (-425 4925);
PAINT AQUA (-425 4925);
DISPLAY INVISIBLE (-425 4925);
FORCEPROP 2 LAST CDS_LIB mstr_discrete
J 0
(-400 4875);
PAINT MONO (-400 4875);
DISPLAY INVISIBLE (-400 4875);
FORCEPROP 2 LAST SEC 1
J 0
(-450 5075);
DISPLAY 0.680851 (-450 5075);
PAINT MONO (-450 5075);
DISPLAY INVISIBLE (-450 5075);
FORCEPROP 2 LAST SEC_TYPE 0402
J 0
(-450 5075);
DISPLAY 1.021277 (-450 5075);
PAINT ORANGE (-450 5075);
DISPLAY INVISIBLE (-450 5075);
FORCEPROP 1 LAST PATH I316
J 0
(-450 5025);
DISPLAY 0.978723 (-450 5025);
PAINT WHITE (-450 5025);
DISPLAY INVISIBLE (-450 5025);
FORCEADD RES..1
(-375 4650);
FORCEPROP 1 LAST VALUE 1.00K
J 2
(-400 4600);
DISPLAY 0.617021 (-400 4600);
PAINT SKYBLUE (-400 4600);
FORCEPROP 1 LAST TOLERANCE 1%
J 0
(-345 4600);
DISPLAY 0.617021 (-345 4600);
PAINT SKYBLUE (-345 4600);
FORCEPROP 1 LASTPIN (-475 4650) $PN 1
J 0
(-463 4662);
DISPLAY 0.617021 (-463 4662);
PAINT ORANGE (-463 4662);
FORCEPROP 1 LAST LOCATION R3P6
J 0
(-400 4700);
DISPLAY 0.617021 (-400 4700);
PAINT AQUA (-400 4700);
FORCEPROP 1 LASTPIN (-275 4650) $PN 2
J 0
(-313 4662);
DISPLAY 0.617021 (-313 4662);
PAINT ORANGE (-313 4662);
FORCEPROP 1 LAST PACK_TYPE 0402
J 0
(-265 4610);
DISPLAY 0.617021 (-265 4610);
PAINT SKYBLUE (-265 4610);
FORCEPROP 1 LAST MATERIAL CHIP
J 0
(-160 4610);
DISPLAY 0.617021 (-160 4610);
PAINT SKYBLUE (-160 4610);
FORCEPROP 1 LAST WATTAGE 1/16W
J 2
(105 4610);
DISPLAY 0.617021 (105 4610);
PAINT SKYBLUE (105 4610);
FORCEPROP 1 LAST PART_NUMBER G21796-026
J 0
(-275 4675);
DISPLAY 0.617021 (-275 4675);
PAINT BLUE (-275 4675);
FORCEPROP 2 LAST BOM_COST SB
J 0
(-425 4500);
PAINT MONO (-425 4500);
DISPLAY INVISIBLE (-425 4500);
FORCEPROP 2 LAST CDS_LOCATION R3P6
J 0
(-400 4700);
DISPLAY 0.617021 (-400 4700);
PAINT AQUA (-400 4700);
DISPLAY INVISIBLE (-400 4700);
FORCEPROP 1 LAST PATH I317
J 0
(-425 4800);
DISPLAY 0.978723 (-425 4800);
PAINT WHITE (-425 4800);
DISPLAY INVISIBLE (-425 4800);
FORCEPROP 2 LAST CDS_LIB mstr_discrete
J 0
(-375 4650);
PAINT MONO (-375 4650);
DISPLAY INVISIBLE (-375 4650);
FORCEPROP 2 LAST ROOM SB
J 0
(-375 4650);
PAINT MONO (-375 4650);
DISPLAY INVISIBLE (-375 4650);
FORCEPROP 2 LAST SEC_TYPE 0402
J 0
(-425 4850);
DISPLAY 1.021277 (-425 4850);
PAINT ORANGE (-425 4850);
DISPLAY INVISIBLE (-425 4850);
FORCEPROP 2 LAST SEC 1
J 0
(-425 4850);
DISPLAY 0.680851 (-425 4850);
PAINT MONO (-425 4850);
DISPLAY INVISIBLE (-425 4850);
FORCEADD RES..1
(-375 4400);
FORCEPROP 1 LAST VALUE 1.00K
J 2
(-400 4350);
DISPLAY 0.617021 (-400 4350);
PAINT SKYBLUE (-400 4350);
FORCEPROP 1 LAST TOLERANCE 1%
J 0
(-345 4350);
DISPLAY 0.617021 (-345 4350);
PAINT SKYBLUE (-345 4350);
FORCEPROP 1 LASTPIN (-475 4400) $PN 1
J 0
(-463 4412);
DISPLAY 0.617021 (-463 4412);
PAINT ORANGE (-463 4412);
FORCEPROP 1 LASTPIN (-275 4400) $PN 2
J 0
(-313 4412);
DISPLAY 0.617021 (-313 4412);
PAINT ORANGE (-313 4412);
FORCEPROP 1 LAST LOCATION R3N15
J 0
(-400 4450);
DISPLAY 0.617021 (-400 4450);
PAINT AQUA (-400 4450);
FORCEPROP 1 LAST PACK_TYPE 0402
J 0
(-265 4360);
DISPLAY 0.617021 (-265 4360);
PAINT SKYBLUE (-265 4360);
FORCEPROP 1 LAST MATERIAL CHIP
J 0
(-160 4360);
DISPLAY 0.617021 (-160 4360);
PAINT SKYBLUE (-160 4360);
FORCEPROP 1 LAST WATTAGE 1/16W
J 2
(105 4360);
DISPLAY 0.617021 (105 4360);
PAINT SKYBLUE (105 4360);
FORCEPROP 1 LAST PART_NUMBER G21796-026
J 0
(-275 4425);
DISPLAY 0.617021 (-275 4425);
PAINT BLUE (-275 4425);
FORCEPROP 2 LAST BOM_COST SB
J 0
(-425 4250);
PAINT MONO (-425 4250);
DISPLAY INVISIBLE (-425 4250);
FORCEPROP 2 LAST CDS_LOCATION R3N15
J 0
(-400 4450);
DISPLAY 0.617021 (-400 4450);
PAINT AQUA (-400 4450);
DISPLAY INVISIBLE (-400 4450);
FORCEPROP 1 LAST PATH I318
J 0
(-425 4550);
DISPLAY 0.978723 (-425 4550);
PAINT WHITE (-425 4550);
DISPLAY INVISIBLE (-425 4550);
FORCEPROP 2 LAST CDS_LIB mstr_discrete
J 0
(-375 4400);
PAINT MONO (-375 4400);
DISPLAY INVISIBLE (-375 4400);
FORCEPROP 2 LAST ROOM SB
J 0
(-375 4400);
PAINT MONO (-375 4400);
DISPLAY INVISIBLE (-375 4400);
FORCEPROP 2 LAST SEC_TYPE 0402
J 0
(-425 4600);
DISPLAY 1.021277 (-425 4600);
PAINT ORANGE (-425 4600);
DISPLAY INVISIBLE (-425 4600);
FORCEPROP 2 LAST SEC 1
J 0
(-425 4600);
DISPLAY 0.680851 (-425 4600);
PAINT MONO (-425 4600);
DISPLAY INVISIBLE (-425 4600);
FORCEADD OFFPAGE..2
(625 4175);
FORCEPROP 2 LAST $XR0 108 
J 0
(814 4175);
DISPLAY 0.638298 (814 4175);
PAINT MONO (814 4175);
FORCEPROP 2 LAST $XR1 121 
J 0
(934 4175);
DISPLAY 0.638298 (934 4175);
PAINT MONO (934 4175);
FORCEPROP 1 LAST OFFPAGE TRUE
J 0
(950 4050);
PAINT GREEN (950 4050);
DISPLAY INVISIBLE (950 4050);
FORCEPROP 1 LAST COMMENT_BODY TRUE
J 0
(580 4080);
DISPLAY 1.170213 (580 4080);
PAINT GREEN (580 4080);
DISPLAY INVISIBLE (580 4080);
FORCEPROP 2 LAST CDS_LIB mstr_standard
J 0
(625 4175);
PAINT MONO (625 4175);
DISPLAY INVISIBLE (625 4175);
FORCEPROP 2 LAST PATH I319
J 0
(800 4250);
DISPLAY 1.021277 (800 4250);
PAINT ORANGE (800 4250);
DISPLAY INVISIBLE (800 4250);
FORCEPROP 2 LAST BOM_COST SB
J 0
(825 4225);
PAINT MONO (825 4225);
DISPLAY INVISIBLE (825 4225);
FORCEADD OFFPAGE..2
(625 3925);
FORCEPROP 2 LAST $XR0 109 
J 0
(814 3925);
DISPLAY 0.638298 (814 3925);
PAINT MONO (814 3925);
FORCEPROP 2 LAST $XR1 121 
J 0
(934 3925);
DISPLAY 0.638298 (934 3925);
PAINT MONO (934 3925);
FORCEPROP 1 LAST COMMENT_BODY TRUE
J 0
(580 3830);
DISPLAY 1.170213 (580 3830);
PAINT GREEN (580 3830);
DISPLAY INVISIBLE (580 3830);
FORCEPROP 2 LAST CDS_LIB mstr_standard
J 0
(625 3925);
PAINT MONO (625 3925);
DISPLAY INVISIBLE (625 3925);
FORCEPROP 2 LAST PATH I320
J 0
(800 4000);
DISPLAY 1.021277 (800 4000);
PAINT ORANGE (800 4000);
DISPLAY INVISIBLE (800 4000);
FORCEPROP 1 LAST OFFPAGE TRUE
J 0
(950 3800);
PAINT GREEN (950 3800);
DISPLAY INVISIBLE (950 3800);
FORCEPROP 2 LAST BOM_COST SB
J 0
(825 3975);
PAINT MONO (825 3975);
DISPLAY INVISIBLE (825 3975);
FORCEADD RES..1
(-375 4175);
FORCEPROP 1 LAST VALUE 1.00K
J 2
(-400 4125);
DISPLAY 0.617021 (-400 4125);
PAINT SKYBLUE (-400 4125);
FORCEPROP 1 LASTPIN (-475 4175) $PN 1
J 0
(-463 4187);
DISPLAY 0.617021 (-463 4187);
PAINT ORANGE (-463 4187);
FORCEPROP 1 LAST TOLERANCE 1%
J 0
(-345 4125);
DISPLAY 0.617021 (-345 4125);
PAINT SKYBLUE (-345 4125);
FORCEPROP 1 LASTPIN (-275 4175) $PN 2
J 0
(-313 4187);
DISPLAY 0.617021 (-313 4187);
PAINT ORANGE (-313 4187);
FORCEPROP 1 LAST LOCATION R3N16
J 0
(-400 4225);
DISPLAY 0.617021 (-400 4225);
PAINT AQUA (-400 4225);
FORCEPROP 1 LAST PACK_TYPE 0402
J 0
(-265 4135);
DISPLAY 0.617021 (-265 4135);
PAINT SKYBLUE (-265 4135);
FORCEPROP 1 LAST MATERIAL CHIP
J 0
(-160 4135);
DISPLAY 0.617021 (-160 4135);
PAINT SKYBLUE (-160 4135);
FORCEPROP 1 LAST WATTAGE 1/16W
J 2
(105 4135);
DISPLAY 0.617021 (105 4135);
PAINT SKYBLUE (105 4135);
FORCEPROP 1 LAST PART_NUMBER G21796-026
J 0
(-275 4200);
DISPLAY 0.617021 (-275 4200);
PAINT BLUE (-275 4200);
FORCEPROP 2 LAST BOM_COST SB
J 0
(-425 4025);
PAINT MONO (-425 4025);
DISPLAY INVISIBLE (-425 4025);
FORCEPROP 2 LAST CDS_LOCATION R3N16
J 0
(-400 4225);
DISPLAY 0.617021 (-400 4225);
PAINT AQUA (-400 4225);
DISPLAY INVISIBLE (-400 4225);
FORCEPROP 2 LAST CDS_LIB mstr_discrete
J 0
(-375 4175);
PAINT MONO (-375 4175);
DISPLAY INVISIBLE (-375 4175);
FORCEPROP 2 LAST ROOM SB
J 0
(-375 4175);
PAINT MONO (-375 4175);
DISPLAY INVISIBLE (-375 4175);
FORCEPROP 1 LAST PATH I321
J 0
(-425 4325);
DISPLAY 0.978723 (-425 4325);
PAINT WHITE (-425 4325);
DISPLAY INVISIBLE (-425 4325);
FORCEPROP 2 LAST SEC 1
J 0
(-425 4375);
DISPLAY 0.680851 (-425 4375);
PAINT MONO (-425 4375);
DISPLAY INVISIBLE (-425 4375);
FORCEPROP 2 LAST SEC_TYPE 0402
J 0
(-425 4375);
DISPLAY 1.021277 (-425 4375);
PAINT ORANGE (-425 4375);
DISPLAY INVISIBLE (-425 4375);
FORCEADD RES..1
(-375 3925);
FORCEPROP 1 LAST VALUE 1.00K
J 2
(-400 3875);
DISPLAY 0.617021 (-400 3875);
PAINT SKYBLUE (-400 3875);
FORCEPROP 1 LASTPIN (-475 3925) $PN 1
J 0
(-463 3937);
DISPLAY 0.617021 (-463 3937);
PAINT ORANGE (-463 3937);
FORCEPROP 1 LAST LOCATION R3P8
J 0
(-400 3975);
DISPLAY 0.617021 (-400 3975);
PAINT AQUA (-400 3975);
FORCEPROP 1 LAST TOLERANCE 1%
J 0
(-345 3875);
DISPLAY 0.617021 (-345 3875);
PAINT SKYBLUE (-345 3875);
FORCEPROP 1 LASTPIN (-275 3925) $PN 2
J 0
(-313 3937);
DISPLAY 0.617021 (-313 3937);
PAINT ORANGE (-313 3937);
FORCEPROP 1 LAST PACK_TYPE 0402
J 0
(-265 3885);
DISPLAY 0.617021 (-265 3885);
PAINT SKYBLUE (-265 3885);
FORCEPROP 1 LAST MATERIAL CHIP
J 0
(-160 3885);
DISPLAY 0.617021 (-160 3885);
PAINT SKYBLUE (-160 3885);
FORCEPROP 1 LAST WATTAGE 1/16W
J 2
(105 3885);
DISPLAY 0.617021 (105 3885);
PAINT SKYBLUE (105 3885);
FORCEPROP 1 LAST PART_NUMBER G21796-026
J 0
(-275 3950);
DISPLAY 0.617021 (-275 3950);
PAINT BLUE (-275 3950);
FORCEPROP 2 LAST BOM_COST SB
J 0
(-425 3775);
PAINT MONO (-425 3775);
DISPLAY INVISIBLE (-425 3775);
FORCEPROP 2 LAST CDS_LOCATION R3P8
J 0
(-400 3975);
DISPLAY 0.617021 (-400 3975);
PAINT AQUA (-400 3975);
DISPLAY INVISIBLE (-400 3975);
FORCEPROP 2 LAST CDS_LIB mstr_discrete
J 0
(-375 3925);
PAINT MONO (-375 3925);
DISPLAY INVISIBLE (-375 3925);
FORCEPROP 2 LAST ROOM SB
J 0
(-375 3925);
PAINT MONO (-375 3925);
DISPLAY INVISIBLE (-375 3925);
FORCEPROP 1 LAST PATH I322
J 0
(-425 4075);
DISPLAY 0.978723 (-425 4075);
PAINT WHITE (-425 4075);
DISPLAY INVISIBLE (-425 4075);
FORCEPROP 2 LAST SEC 1
J 0
(-425 4125);
DISPLAY 0.680851 (-425 4125);
PAINT MONO (-425 4125);
DISPLAY INVISIBLE (-425 4125);
FORCEPROP 2 LAST SEC_TYPE 0402
J 0
(-425 4125);
DISPLAY 1.021277 (-425 4125);
PAINT ORANGE (-425 4125);
DISPLAY INVISIBLE (-425 4125);
FORCEADD OFFPAGE..2
(-3925 1300);
FORCEPROP 2 LAST $XR0 108 
J 0
(-3736 1300);
DISPLAY 0.638298 (-3736 1300);
PAINT MONO (-3736 1300);
FORCEPROP 2 LAST $XR1 119 
J 0
(-3616 1300);
DISPLAY 0.638298 (-3616 1300);
PAINT MONO (-3616 1300);
FORCEPROP 1 LAST COMMENT_BODY TRUE
J 0
(-3970 1205);
DISPLAY 1.170213 (-3970 1205);
PAINT GREEN (-3970 1205);
DISPLAY INVISIBLE (-3970 1205);
FORCEPROP 2 LAST CDS_LIB mstr_standard
J 0
(-3925 1300);
PAINT MONO (-3925 1300);
DISPLAY INVISIBLE (-3925 1300);
FORCEPROP 1 LAST OFFPAGE TRUE
J 0
(-3600 1175);
PAINT GREEN (-3600 1175);
DISPLAY INVISIBLE (-3600 1175);
FORCEPROP 2 LAST BOM_COST SB
J 0
(-3725 1350);
PAINT MONO (-3725 1350);
DISPLAY INVISIBLE (-3725 1350);
FORCEPROP 2 LAST PATH I325
J 0
(-3750 1375);
DISPLAY 1.021277 (-3750 1375);
PAINT ORANGE (-3750 1375);
DISPLAY INVISIBLE (-3750 1375);
FORCEADD RES..1
(-4800 1300);
FORCEPROP 1 LAST WATTAGE 1/16W
J 2
(-4875 1250);
DISPLAY 0.617021 (-4875 1250);
PAINT SKYBLUE (-4875 1250);
FORCEPROP 1 LAST VALUE 4.75K
J 2
(-4900 1300);
DISPLAY 0.617021 (-4900 1300);
PAINT SKYBLUE (-4900 1300);
FORCEPROP 1 LASTPIN (-4900 1300) $PN 1
J 0
(-4888 1312);
DISPLAY 0.617021 (-4888 1312);
PAINT ORANGE (-4888 1312);
FORCEPROP 1 LAST LOCATION R8C1
J 0
(-4850 1350);
DISPLAY 0.617021 (-4850 1350);
PAINT AQUA (-4850 1350);
FORCEPROP 1 LASTPIN (-4700 1300) $PN 2
J 0
(-4738 1312);
DISPLAY 0.617021 (-4738 1312);
PAINT ORANGE (-4738 1312);
FORCEPROP 1 LAST PART_NUMBER G21796-072
J 0
(-4875 1250);
DISPLAY 0.617021 (-4875 1250);
PAINT BLUE (-4875 1250);
FORCEPROP 1 LAST TOLERANCE 1%
J 0
(-4650 1250);
DISPLAY 0.617021 (-4650 1250);
PAINT SKYBLUE (-4650 1250);
FORCEPROP 1 LAST PACK_TYPE 0402
J 0
(-4675 1300);
DISPLAY 0.617021 (-4675 1300);
PAINT SKYBLUE (-4675 1300);
FORCEPROP 1 LAST MATERIAL CHIP
J 0
(-4575 1250);
DISPLAY 0.617021 (-4575 1250);
PAINT SKYBLUE (-4575 1250);
FORCEPROP 2 LAST CDS_LOCATION R8C1
J 0
(-4850 1350);
DISPLAY 0.617021 (-4850 1350);
PAINT AQUA (-4850 1350);
DISPLAY INVISIBLE (-4850 1350);
FORCEPROP 2 LAST CDS_LIB mstr_discrete
J 0
(-4800 1300);
PAINT MONO (-4800 1300);
DISPLAY INVISIBLE (-4800 1300);
FORCEPROP 2 LAST ROOM SB_PU_PD
J 0
(-4850 1400);
DISPLAY 1.021277 (-4850 1400);
PAINT ORANGE (-4850 1400);
DISPLAY INVISIBLE (-4850 1400);
FORCEPROP 1 LAST PATH I326
J 0
(-4850 1450);
DISPLAY 0.978723 (-4850 1450);
PAINT WHITE (-4850 1450);
DISPLAY INVISIBLE (-4850 1450);
FORCEPROP 2 LAST SEC 1
J 0
(-4850 1500);
DISPLAY 0.680851 (-4850 1500);
PAINT MONO (-4850 1500);
DISPLAY INVISIBLE (-4850 1500);
FORCEPROP 2 LAST SEC_TYPE 0402
J 0
(-4850 1500);
DISPLAY 1.021277 (-4850 1500);
PAINT ORANGE (-4850 1500);
DISPLAY INVISIBLE (-4850 1500);
FORCEADD RES..1
(-4800 1125);
FORCEPROP 1 LAST VALUE 4.75K
J 2
(-4900 1125);
DISPLAY 0.617021 (-4900 1125);
PAINT SKYBLUE (-4900 1125);
FORCEPROP 1 LAST WATTAGE 1/16W
J 2
(-4875 1075);
DISPLAY 0.617021 (-4875 1075);
PAINT SKYBLUE (-4875 1075);
FORCEPROP 1 LASTPIN (-4900 1125) $PN 1
J 0
(-4888 1137);
DISPLAY 0.617021 (-4888 1137);
PAINT ORANGE (-4888 1137);
FORCEPROP 1 LASTPIN (-4700 1125) $PN 2
J 0
(-4738 1137);
DISPLAY 0.617021 (-4738 1137);
PAINT ORANGE (-4738 1137);
FORCEPROP 1 LAST LOCATION R8C7
J 0
(-4850 1175);
DISPLAY 0.617021 (-4850 1175);
PAINT AQUA (-4850 1175);
FORCEPROP 1 LAST PART_NUMBER G21796-072
J 0
(-4875 1075);
DISPLAY 0.617021 (-4875 1075);
PAINT BLUE (-4875 1075);
FORCEPROP 1 LAST TOLERANCE 1%
J 0
(-4650 1075);
DISPLAY 0.617021 (-4650 1075);
PAINT SKYBLUE (-4650 1075);
FORCEPROP 1 LAST PACK_TYPE 0402
J 0
(-4675 1125);
DISPLAY 0.617021 (-4675 1125);
PAINT SKYBLUE (-4675 1125);
FORCEPROP 1 LAST MATERIAL CHIP
J 0
(-4575 1075);
DISPLAY 0.617021 (-4575 1075);
PAINT SKYBLUE (-4575 1075);
FORCEPROP 2 LAST BOM_COST SB
J 0
(-4850 975);
PAINT MONO (-4850 975);
DISPLAY INVISIBLE (-4850 975);
FORCEPROP 2 LAST CDS_LOCATION R8C7
J 0
(-4850 1175);
DISPLAY 0.617021 (-4850 1175);
PAINT AQUA (-4850 1175);
DISPLAY INVISIBLE (-4850 1175);
FORCEPROP 2 LAST CDS_LIB mstr_discrete
J 0
(-4800 1125);
PAINT MONO (-4800 1125);
DISPLAY INVISIBLE (-4800 1125);
FORCEPROP 2 LAST ROOM SB_PU_PD
J 0
(-4800 1125);
PAINT MONO (-4800 1125);
DISPLAY INVISIBLE (-4800 1125);
FORCEPROP 1 LAST PATH I327
J 0
(-4850 1275);
DISPLAY 0.978723 (-4850 1275);
PAINT WHITE (-4850 1275);
DISPLAY INVISIBLE (-4850 1275);
FORCEPROP 2 LAST SEC_TYPE 0402
J 0
(-4850 1325);
DISPLAY 1.021277 (-4850 1325);
PAINT ORANGE (-4850 1325);
DISPLAY INVISIBLE (-4850 1325);
FORCEPROP 2 LAST SEC 1
J 0
(-4850 1325);
DISPLAY 0.680851 (-4850 1325);
PAINT MONO (-4850 1325);
DISPLAY INVISIBLE (-4850 1325);
FORCEADD OFFPAGE..2
(-3925 1125);
FORCEPROP 2 LAST $XR0 108 
J 0
(-3736 1125);
DISPLAY 0.638298 (-3736 1125);
PAINT MONO (-3736 1125);
FORCEPROP 2 LAST $XR1 119 
J 0
(-3616 1125);
DISPLAY 0.638298 (-3616 1125);
PAINT MONO (-3616 1125);
FORCEPROP 1 LAST OFFPAGE TRUE
J 0
(-3600 1000);
PAINT GREEN (-3600 1000);
DISPLAY INVISIBLE (-3600 1000);
FORCEPROP 1 LAST COMMENT_BODY TRUE
J 0
(-3970 1030);
DISPLAY 1.170213 (-3970 1030);
PAINT GREEN (-3970 1030);
DISPLAY INVISIBLE (-3970 1030);
FORCEPROP 2 LAST CDS_LIB mstr_standard
J 0
(-3925 1125);
PAINT MONO (-3925 1125);
DISPLAY INVISIBLE (-3925 1125);
FORCEPROP 2 LAST PATH I328
J 0
(-3750 1200);
DISPLAY 1.021277 (-3750 1200);
PAINT ORANGE (-3750 1200);
DISPLAY INVISIBLE (-3750 1200);
FORCEPROP 2 LAST BOM_COST SB
J 0
(-3725 1175);
PAINT MONO (-3725 1175);
DISPLAY INVISIBLE (-3725 1175);
FORCEADD RES..1
(-4700 4700);
FORCEPROP 1 LAST WATTAGE 1/16W
J 2
(-4775 4650);
DISPLAY 0.617021 (-4775 4650);
PAINT SKYBLUE (-4775 4650);
FORCEPROP 1 LAST VALUE 1.00K
J 2
(-4800 4700);
DISPLAY 0.617021 (-4800 4700);
PAINT SKYBLUE (-4800 4700);
FORCEPROP 1 LASTPIN (-4800 4700) $PN 1
J 0
(-4788 4712);
DISPLAY 0.617021 (-4788 4712);
PAINT ORANGE (-4788 4712);
FORCEPROP 1 LAST LOCATION R7D7
J 0
(-4750 4750);
DISPLAY 0.617021 (-4750 4750);
PAINT AQUA (-4750 4750);
FORCEPROP 1 LASTPIN (-4600 4700) $PN 2
J 0
(-4638 4712);
DISPLAY 0.617021 (-4638 4712);
PAINT ORANGE (-4638 4712);
FORCEPROP 1 LAST PART_NUMBER G21796-026
J 0
(-4775 4650);
DISPLAY 0.617021 (-4775 4650);
PAINT BLUE (-4775 4650);
FORCEPROP 1 LAST MATERIAL CHIP
J 0
(-4475 4650);
DISPLAY 0.617021 (-4475 4650);
PAINT SKYBLUE (-4475 4650);
FORCEPROP 1 LAST PACK_TYPE 0402
J 0
(-4575 4700);
DISPLAY 0.617021 (-4575 4700);
PAINT SKYBLUE (-4575 4700);
FORCEPROP 1 LAST TOLERANCE 1%
J 0
(-4550 4650);
DISPLAY 0.617021 (-4550 4650);
PAINT SKYBLUE (-4550 4650);
FORCEPROP 2 LAST BOM_COST SB_PU_PD
J 0
(-4750 4550);
PAINT MONO (-4750 4550);
DISPLAY INVISIBLE (-4750 4550);
FORCEPROP 2 LAST CDS_LOCATION R7D7
J 0
(-4750 4750);
DISPLAY 0.617021 (-4750 4750);
PAINT AQUA (-4750 4750);
DISPLAY INVISIBLE (-4750 4750);
FORCEPROP 2 LAST CDS_LIB mstr_discrete
J 0
(-4700 4700);
PAINT ORANGE (-4700 4700);
DISPLAY INVISIBLE (-4700 4700);
FORCEPROP 2 LAST ROOM SB
J 0
(-4700 4700);
PAINT MONO (-4700 4700);
DISPLAY INVISIBLE (-4700 4700);
FORCEPROP 1 LAST PATH I331
J 0
(-4750 4850);
DISPLAY 0.978723 (-4750 4850);
PAINT WHITE (-4750 4850);
DISPLAY INVISIBLE (-4750 4850);
FORCEPROP 2 LAST SEC_TYPE 0402
J 0
(-4750 4900);
DISPLAY 1.021277 (-4750 4900);
PAINT ORANGE (-4750 4900);
DISPLAY INVISIBLE (-4750 4900);
FORCEPROP 2 LAST SEC 1
J 0
(-4750 4900);
DISPLAY 0.680851 (-4750 4900);
PAINT MONO (-4750 4900);
DISPLAY INVISIBLE (-4750 4900);
FORCEADD RES..1
(-4700 5100);
FORCEPROP 1 LAST WATTAGE 1/16W
J 2
(-4775 5050);
DISPLAY 0.617021 (-4775 5050);
PAINT SKYBLUE (-4775 5050);
FORCEPROP 1 LAST PART_NUMBER G21796-026
J 0
(-4775 5050);
DISPLAY 0.617021 (-4775 5050);
PAINT BLUE (-4775 5050);
FORCEPROP 1 LAST MATERIAL CHIP
J 0
(-4475 5050);
DISPLAY 0.617021 (-4475 5050);
PAINT SKYBLUE (-4475 5050);
FORCEPROP 1 LAST TOLERANCE 1%
J 0
(-4550 5050);
DISPLAY 0.617021 (-4550 5050);
PAINT SKYBLUE (-4550 5050);
FORCEPROP 1 LAST VALUE 1.00K
J 2
(-4800 5100);
DISPLAY 0.617021 (-4800 5100);
PAINT SKYBLUE (-4800 5100);
FORCEPROP 1 LAST PACK_TYPE 0402
J 0
(-4575 5100);
DISPLAY 0.617021 (-4575 5100);
PAINT SKYBLUE (-4575 5100);
FORCEPROP 1 LASTPIN (-4600 5100) $PN 2
J 0
(-4638 5112);
DISPLAY 0.617021 (-4638 5112);
PAINT ORANGE (-4638 5112);
FORCEPROP 1 LASTPIN (-4800 5100) $PN 1
J 0
(-4788 5112);
DISPLAY 0.617021 (-4788 5112);
PAINT ORANGE (-4788 5112);
FORCEPROP 1 LAST LOCATION R7D2
J 0
(-4750 5150);
DISPLAY 0.617021 (-4750 5150);
PAINT AQUA (-4750 5150);
FORCEPROP 2 LAST BOM_COST SB_PU_PD
J 0
(-4750 4950);
PAINT MONO (-4750 4950);
DISPLAY INVISIBLE (-4750 4950);
FORCEPROP 2 LAST ROOM SB
J 0
(-4700 5100);
PAINT MONO (-4700 5100);
DISPLAY INVISIBLE (-4700 5100);
FORCEPROP 2 LAST CDS_LIB mstr_discrete
J 0
(-4700 5100);
PAINT ORANGE (-4700 5100);
DISPLAY INVISIBLE (-4700 5100);
FORCEPROP 1 LAST PATH I332
J 0
(-4750 5250);
DISPLAY 0.978723 (-4750 5250);
PAINT WHITE (-4750 5250);
DISPLAY INVISIBLE (-4750 5250);
FORCEPROP 2 LAST CDS_LOCATION R7D2
J 0
(-4750 5150);
DISPLAY 0.617021 (-4750 5150);
PAINT AQUA (-4750 5150);
DISPLAY INVISIBLE (-4750 5150);
FORCEPROP 2 LAST SEC 1
J 0
(-4750 5300);
DISPLAY 0.680851 (-4750 5300);
PAINT MONO (-4750 5300);
DISPLAY INVISIBLE (-4750 5300);
FORCEPROP 2 LAST SEC_TYPE 0402
J 0
(-4750 5300);
DISPLAY 1.021277 (-4750 5300);
PAINT ORANGE (-4750 5300);
DISPLAY INVISIBLE (-4750 5300);
FORCEADD RES..1
(-2500 3150);
FORCEPROP 1 LAST WATTAGE 1/16W
J 2
(-2575 3100);
DISPLAY 0.617021 (-2575 3100);
PAINT SKYBLUE (-2575 3100);
FORCEPROP 1 LAST VALUE 4.75K
J 2
(-2600 3150);
DISPLAY 0.617021 (-2600 3150);
PAINT SKYBLUE (-2600 3150);
FORCEPROP 1 LAST PART_NUMBER G21796-072
J 0
(-2575 3100);
DISPLAY 0.617021 (-2575 3100);
PAINT BLUE (-2575 3100);
FORCEPROP 1 LASTPIN (-2600 3150) $PN 1
J 0
(-2588 3162);
DISPLAY 0.617021 (-2588 3162);
PAINT ORANGE (-2588 3162);
FORCEPROP 1 LAST LOCATION R8C25
J 0
(-2550 3200);
DISPLAY 0.617021 (-2550 3200);
PAINT AQUA (-2550 3200);
FORCEPROP 1 LASTPIN (-2400 3150) $PN 2
J 0
(-2438 3162);
DISPLAY 0.617021 (-2438 3162);
PAINT ORANGE (-2438 3162);
FORCEPROP 1 LAST TOLERANCE 1%
J 0
(-2350 3100);
DISPLAY 0.617021 (-2350 3100);
PAINT SKYBLUE (-2350 3100);
FORCEPROP 1 LAST PACK_TYPE 0402
J 0
(-2375 3150);
DISPLAY 0.617021 (-2375 3150);
PAINT SKYBLUE (-2375 3150);
FORCEPROP 1 LAST MATERIAL CHIP
J 0
(-2275 3100);
DISPLAY 0.617021 (-2275 3100);
PAINT SKYBLUE (-2275 3100);
FORCEPROP 2 LAST CDS_LOCATION R8C25
J 0
(-2550 3200);
DISPLAY 0.617021 (-2550 3200);
PAINT AQUA (-2550 3200);
DISPLAY INVISIBLE (-2550 3200);
FORCEPROP 2 LAST ROOM SB_PU_PD
J 0
(-2550 3250);
DISPLAY 1.021277 (-2550 3250);
PAINT ORANGE (-2550 3250);
DISPLAY INVISIBLE (-2550 3250);
FORCEPROP 2 LAST CDS_LIB mstr_discrete
J 0
(-2500 3150);
PAINT ORANGE (-2500 3150);
DISPLAY INVISIBLE (-2500 3150);
FORCEPROP 1 LAST PATH I333
J 0
(-2550 3300);
DISPLAY 0.978723 (-2550 3300);
PAINT WHITE (-2550 3300);
DISPLAY INVISIBLE (-2550 3300);
FORCEPROP 2 LAST SEC_TYPE 0402
J 0
(-2550 3350);
DISPLAY 1.021277 (-2550 3350);
PAINT ORANGE (-2550 3350);
DISPLAY INVISIBLE (-2550 3350);
FORCEPROP 2 LAST SEC 1
J 0
(-2550 3350);
DISPLAY 0.680851 (-2550 3350);
PAINT MONO (-2550 3350);
DISPLAY INVISIBLE (-2550 3350);
FORCEADD OFFPAGE..2
(-1600 3150);
FORCEPROP 2 LAST $XR0 120 
J 0
(-1411 3150);
DISPLAY 0.638298 (-1411 3150);
PAINT MONO (-1411 3150);
FORCEPROP 2 LAST $XR1 119 
J 0
(-1291 3150);
DISPLAY 0.638298 (-1291 3150);
PAINT MONO (-1291 3150);
FORCEPROP 2 LAST $XR2 143 
J 0
(-1171 3150);
DISPLAY 0.638298 (-1171 3150);
PAINT MONO (-1171 3150);
FORCEPROP 1 LAST OFFPAGE TRUE
J 0
(-1275 3025);
PAINT GREEN (-1275 3025);
DISPLAY INVISIBLE (-1275 3025);
FORCEPROP 1 LAST COMMENT_BODY TRUE
J 0
(-1645 3055);
DISPLAY 1.170213 (-1645 3055);
PAINT GREEN (-1645 3055);
DISPLAY INVISIBLE (-1645 3055);
FORCEPROP 2 LAST CDS_LIB mstr_standard
J 0
(-1600 3150);
PAINT ORANGE (-1600 3150);
DISPLAY INVISIBLE (-1600 3150);
FORCEPROP 2 LAST BOM_COST SB
J 0
(-1400 3200);
PAINT MONO (-1400 3200);
DISPLAY INVISIBLE (-1400 3200);
FORCEPROP 2 LAST PATH I334
J 0
(-1425 3225);
DISPLAY 1.021277 (-1425 3225);
PAINT ORANGE (-1425 3225);
DISPLAY INVISIBLE (-1425 3225);
FORCEPROP 2 LAST $XR3 146 
J 0
(-1171 3150);
DISPLAY 0.638298 (-1171 3150);
PAINT MONO (-1171 3150);
FORCEADD P3V3_STBY..1
(-2775 3425);
FORCEPROP 3 LASTPIN (-2775 3375) SIG_NAME P3V3_STBY\g
J 0
(-2765 3385);
DISPLAY 0.659574 (-2765 3385);
PAINT MONO (-2765 3385);
DISPLAY INVISIBLE (-2765 3385);
FORCEPROP 1 LAST HDL_POWER P3V3_STBY
J 0
(-3075 3300);
DISPLAY 0.872340 (-3075 3300);
PAINT ORANGE (-3075 3300);
DISPLAY INVISIBLE (-3075 3300);
FORCEPROP 1 LAST VOLTAGE 3.3V
J 0
(-2820 3382);
DISPLAY 0.340426 (-2820 3382);
PAINT SKYBLUE (-2820 3382);
DISPLAY INVISIBLE (-2820 3382);
FORCEPROP 1 LAST BODY_TYPE PLUMBING
J 0
(-2820 3382);
DISPLAY 0.340426 (-2820 3382);
PAINT GREEN (-2820 3382);
DISPLAY INVISIBLE (-2820 3382);
FORCEPROP 2 LAST CDS_LIB mstr_symbols
J 0
(-2775 3425);
PAINT ORANGE (-2775 3425);
DISPLAY INVISIBLE (-2775 3425);
FORCEPROP 1 LAST SIZE 1B
J 0
(-2730 3447);
DISPLAY 0.340426 (-2730 3447);
PAINT GREEN (-2730 3447);
DISPLAY INVISIBLE (-2730 3447);
FORCEPROP 1 LAST PATH I335
J 0
(-2730 3427);
DISPLAY 0.340426 (-2730 3427);
PAINT GREEN (-2730 3427);
DISPLAY INVISIBLE (-2730 3427);
FORCEADD P1V05_PCH_STBY..1
(-625 5325);
FORCEPROP 3 LASTPIN (-625 5275) SIG_NAME P1V05_PCH_STBY\g
J 0
(-615 5285);
DISPLAY 0.659574 (-615 5285);
PAINT MONO (-615 5285);
DISPLAY INVISIBLE (-615 5285);
FORCEPROP 1 LAST PATH I339
J 0
(-575 5350);
DISPLAY 0.872340 (-575 5350);
PAINT AQUA (-575 5350);
DISPLAY INVISIBLE (-575 5350);
FORCEPROP 1 LAST BODY_TYPE PLUMBING
J 0
(-670 5282);
DISPLAY 0.340426 (-670 5282);
PAINT GREEN (-670 5282);
DISPLAY INVISIBLE (-670 5282);
FORCEPROP 2 LAST CDS_LIB mstr_symbols
J 0
(-625 5325);
PAINT ORANGE (-625 5325);
DISPLAY INVISIBLE (-625 5325);
FORCEPROP 1 LAST HDL_POWER P1V05_PCH_STBY
J 0
(-625 5375);
DISPLAY 0.872340 (-625 5375);
PAINT GREEN (-625 5375);
DISPLAY INVISIBLE (-625 5375);
FORCEPROP 1 LAST VOLTAGE 1.05V
J 0
(-670 5282);
DISPLAY 0.340426 (-670 5282);
PAINT SKYBLUE (-670 5282);
DISPLAY INVISIBLE (-670 5282);
FORCEADD OFFPAGE..2
(-1575 2700);
FORCEPROP 2 LAST $XR0 120 
J 0
(-1386 2700);
DISPLAY 0.638298 (-1386 2700);
PAINT MONO (-1386 2700);
FORCEPROP 2 LAST $XR1 145 
J 0
(-1266 2700);
DISPLAY 0.638298 (-1266 2700);
PAINT MONO (-1266 2700);
FORCEPROP 2 LAST $XR2 ?
J 0
(-1266 2700);
DISPLAY 0.638298 (-1266 2700);
PAINT MONO (-1266 2700);
FORCEPROP 1 LAST COMMENT_BODY TRUE
J 0
(-1620 2605);
DISPLAY 1.170213 (-1620 2605);
PAINT GREEN (-1620 2605);
DISPLAY INVISIBLE (-1620 2605);
FORCEPROP 2 LAST CDS_LIB mstr_standard
J 0
(-1575 2700);
PAINT ORANGE (-1575 2700);
DISPLAY INVISIBLE (-1575 2700);
FORCEPROP 2 LAST PATH I340
J 0
(-1400 2775);
DISPLAY 1.021277 (-1400 2775);
PAINT ORANGE (-1400 2775);
DISPLAY INVISIBLE (-1400 2775);
FORCEPROP 1 LAST OFFPAGE TRUE
J 0
(-1250 2575);
PAINT GREEN (-1250 2575);
DISPLAY INVISIBLE (-1250 2575);
FORCEPROP 2 LAST BOM_COST SB
J 0
(-1250 2750);
PAINT MONO (-1250 2750);
DISPLAY INVISIBLE (-1250 2750);
FORCEADD RES..1
(-2475 2700);
FORCEPROP 1 LAST WATTAGE 1/16W
J 2
(-2500 2550);
DISPLAY 0.617021 (-2500 2550);
PAINT SKYBLUE (-2500 2550);
FORCEPROP 1 LAST VALUE 4.75K
J 2
(-2500 2600);
DISPLAY 0.617021 (-2500 2600);
PAINT SKYBLUE (-2500 2600);
FORCEPROP 1 LASTPIN (-2575 2700) $PN 1
J 0
(-2563 2712);
DISPLAY 0.617021 (-2563 2712);
PAINT ORANGE (-2563 2712);
FORCEPROP 1 LAST PACK_TYPE 0402
J 0
(-2225 2550);
DISPLAY 0.617021 (-2225 2550);
PAINT SKYBLUE (-2225 2550);
FORCEPROP 1 LAST MATERIAL CHIP
J 0
(-2475 2550);
DISPLAY 0.617021 (-2475 2550);
PAINT SKYBLUE (-2475 2550);
FORCEPROP 1 LAST LOCATION R2N32
J 0
(-2525 2750);
DISPLAY 0.617021 (-2525 2750);
PAINT AQUA (-2525 2750);
FORCEPROP 1 LAST TOLERANCE 1%
J 0
(-2475 2600);
DISPLAY 0.617021 (-2475 2600);
PAINT SKYBLUE (-2475 2600);
FORCEPROP 1 LASTPIN (-2375 2700) $PN 2
J 0
(-2413 2712);
DISPLAY 0.617021 (-2413 2712);
PAINT ORANGE (-2413 2712);
FORCEPROP 1 LAST PART_NUMBER G21796-072
J 0
(-2525 2800);
DISPLAY 0.617021 (-2525 2800);
PAINT BLUE (-2525 2800);
FORCEPROP 2 LAST BOM_COST SB
J 0
(-2525 2550);
PAINT MONO (-2525 2550);
DISPLAY INVISIBLE (-2525 2550);
FORCEPROP 2 LAST CDS_LIB mstr_discrete
J 0
(-2475 2700);
PAINT ORANGE (-2475 2700);
DISPLAY INVISIBLE (-2475 2700);
FORCEPROP 2 LAST ROOM SB
J 0
(-2475 2700);
PAINT MONO (-2475 2700);
DISPLAY INVISIBLE (-2475 2700);
FORCEPROP 1 LAST PATH I341
J 0
(-2525 2850);
DISPLAY 0.978723 (-2525 2850);
PAINT WHITE (-2525 2850);
DISPLAY INVISIBLE (-2525 2850);
FORCEPROP 2 LAST SEC 1
J 0
(-2525 2900);
DISPLAY 0.680851 (-2525 2900);
PAINT MONO (-2525 2900);
DISPLAY INVISIBLE (-2525 2900);
FORCEPROP 2 LAST SEC_TYPE 0402
J 0
(-2525 2900);
DISPLAY 1.021277 (-2525 2900);
PAINT ORANGE (-2525 2900);
DISPLAY INVISIBLE (-2525 2900);
FORCEADD P3V3_STBY..1
(-2800 2875);
FORCEPROP 3 LASTPIN (-2800 2825) SIG_NAME P3V3_STBY\g
J 0
(-2790 2835);
DISPLAY 0.659574 (-2790 2835);
PAINT MONO (-2790 2835);
DISPLAY INVISIBLE (-2790 2835);
FORCEPROP 1 LAST HDL_POWER P3V3_STBY
J 0
(-3100 2750);
DISPLAY 0.872340 (-3100 2750);
PAINT ORANGE (-3100 2750);
DISPLAY INVISIBLE (-3100 2750);
FORCEPROP 1 LAST BODY_TYPE PLUMBING
J 0
(-2845 2832);
DISPLAY 0.340426 (-2845 2832);
PAINT GREEN (-2845 2832);
DISPLAY INVISIBLE (-2845 2832);
FORCEPROP 1 LAST VOLTAGE 3.3V
J 0
(-2845 2832);
DISPLAY 0.340426 (-2845 2832);
PAINT SKYBLUE (-2845 2832);
DISPLAY INVISIBLE (-2845 2832);
FORCEPROP 2 LAST CDS_LIB mstr_symbols
J 0
(-2800 2875);
PAINT ORANGE (-2800 2875);
DISPLAY INVISIBLE (-2800 2875);
FORCEPROP 1 LAST SIZE 1B
J 0
(-2755 2897);
DISPLAY 0.340426 (-2755 2897);
PAINT GREEN (-2755 2897);
DISPLAY INVISIBLE (-2755 2897);
FORCEPROP 1 LAST PATH I342
J 0
(-2755 2877);
DISPLAY 0.340426 (-2755 2877);
PAINT GREEN (-2755 2877);
DISPLAY INVISIBLE (-2755 2877);
FORCEADD RES..1
(-375 2725);
FORCEPROP 1 LAST VALUE 1.5K
J 2
(-500 2675);
DISPLAY 0.617021 (-500 2675);
PAINT SKYBLUE (-500 2675);
FORCEPROP 1 LASTPIN (-475 2725) $PN 1
J 0
(-463 2737);
DISPLAY 0.617021 (-463 2737);
PAINT ORANGE (-463 2737);
FORCEPROP 1 LAST TOLERANCE 1%
J 0
(-450 2675);
DISPLAY 0.617021 (-450 2675);
PAINT SKYBLUE (-450 2675);
FORCEPROP 1 LAST LOCATION R2M8
J 0
(-400 2775);
DISPLAY 0.617021 (-400 2775);
PAINT AQUA (-400 2775);
FORCEPROP 1 LASTPIN (-275 2725) $PN 2
J 0
(-313 2737);
DISPLAY 0.617021 (-313 2737);
PAINT ORANGE (-313 2737);
FORCEPROP 1 LAST PART_NUMBER G21796-003
J 0
(-275 2675);
DISPLAY 0.617021 (-275 2675);
PAINT BLUE (-275 2675);
FORCEPROP 1 LAST MATERIAL CHIP
J 0
(-50 2675);
DISPLAY 0.617021 (-50 2675);
PAINT SKYBLUE (-50 2675);
FORCEPROP 1 LAST WATTAGE 1/16W
J 2
(250 2675);
DISPLAY 0.617021 (250 2675);
PAINT SKYBLUE (250 2675);
FORCEPROP 1 LAST PACK_TYPE 0402
J 0
(300 2675);
DISPLAY 0.617021 (300 2675);
PAINT SKYBLUE (300 2675);
FORCEPROP 2 LAST BOM_COST SB
J 0
(-425 2575);
PAINT MONO (-425 2575);
DISPLAY INVISIBLE (-425 2575);
FORCEPROP 2 LAST CDS_LIB mstr_discrete
J 0
(-375 2725);
PAINT ORANGE (-375 2725);
DISPLAY INVISIBLE (-375 2725);
FORCEPROP 2 LAST ROOM SB
J 0
(-375 2725);
PAINT MONO (-375 2725);
DISPLAY INVISIBLE (-375 2725);
FORCEPROP 2 LAST SEC 1
J 0
(-425 2925);
DISPLAY 0.680851 (-425 2925);
PAINT MONO (-425 2925);
DISPLAY INVISIBLE (-425 2925);
FORCEPROP 2 LAST SEC_TYPE 0402
J 0
(-425 2925);
DISPLAY 1.021277 (-425 2925);
PAINT ORANGE (-425 2925);
DISPLAY INVISIBLE (-425 2925);
FORCEPROP 1 LAST PATH I349
J 0
(-425 2875);
DISPLAY 0.978723 (-425 2875);
PAINT WHITE (-425 2875);
DISPLAY INVISIBLE (-425 2875);
FORCEADD OFFPAGE..2
(625 2725);
FORCEPROP 2 LAST $XR0 22 
J 0
(814 2725);
DISPLAY 0.638298 (814 2725);
PAINT MONO (814 2725);
FORCEPROP 2 LAST $XR1 118 
J 0
(904 2725);
DISPLAY 0.638298 (904 2725);
PAINT MONO (904 2725);
FORCEPROP 2 LAST $XR2 120 
J 0
(1024 2725);
DISPLAY 0.638298 (1024 2725);
PAINT MONO (1024 2725);
FORCEPROP 2 LAST $XR3 145 
J 0
(814 2689);
DISPLAY 0.638298 (814 2689);
PAINT MONO (814 2689);
FORCEPROP 1 LAST COMMENT_BODY TRUE
J 0
(580 2630);
DISPLAY 1.170213 (580 2630);
PAINT GREEN (580 2630);
DISPLAY INVISIBLE (580 2630);
FORCEPROP 2 LAST CDS_LIB mstr_standard
J 0
(625 2725);
PAINT ORANGE (625 2725);
DISPLAY INVISIBLE (625 2725);
FORCEPROP 2 LAST PATH I350
J 0
(925 2775);
DISPLAY 1.021277 (925 2775);
PAINT ORANGE (925 2775);
DISPLAY INVISIBLE (925 2775);
FORCEPROP 1 LAST OFFPAGE TRUE
J 0
(950 2600);
PAINT GREEN (950 2600);
DISPLAY INVISIBLE (950 2600);
FORCEPROP 2 LAST BOM_COST SB
J 0
(825 2775);
PAINT MONO (825 2775);
DISPLAY INVISIBLE (825 2775);
FORCEADD OFFPAGE..2
(625 2475);
FORCEPROP 2 LAST $XR0 56 
J 0
(814 2475);
DISPLAY 0.638298 (814 2475);
PAINT MONO (814 2475);
FORCEPROP 2 LAST $XR1 120 
J 0
(904 2475);
DISPLAY 0.638298 (904 2475);
PAINT MONO (904 2475);
FORCEPROP 2 LAST $XR2 145 
J 0
(1024 2475);
DISPLAY 0.638298 (1024 2475);
PAINT MONO (1024 2475);
FORCEPROP 1 LAST COMMENT_BODY TRUE
J 0
(580 2380);
DISPLAY 1.170213 (580 2380);
PAINT GREEN (580 2380);
DISPLAY INVISIBLE (580 2380);
FORCEPROP 2 LAST CDS_LIB mstr_standard
J 0
(625 2475);
PAINT ORANGE (625 2475);
DISPLAY INVISIBLE (625 2475);
FORCEPROP 1 LAST OFFPAGE TRUE
J 0
(950 2350);
PAINT GREEN (950 2350);
DISPLAY INVISIBLE (950 2350);
FORCEPROP 2 LAST PATH I351
J 0
(925 2525);
DISPLAY 1.021277 (925 2525);
PAINT ORANGE (925 2525);
DISPLAY INVISIBLE (925 2525);
FORCEPROP 2 LAST BOM_COST SB
J 0
(825 2525);
PAINT MONO (825 2525);
DISPLAY INVISIBLE (825 2525);
FORCEADD RES..1
(-375 2475);
FORCEPROP 1 LAST VALUE 1.5K
J 2
(-500 2425);
DISPLAY 0.617021 (-500 2425);
PAINT SKYBLUE (-500 2425);
FORCEPROP 1 LAST TOLERANCE 1%
J 0
(-475 2425);
DISPLAY 0.617021 (-475 2425);
PAINT SKYBLUE (-475 2425);
FORCEPROP 1 LASTPIN (-475 2475) $PN 1
J 0
(-463 2487);
DISPLAY 0.617021 (-463 2487);
PAINT ORANGE (-463 2487);
FORCEPROP 1 LAST LOCATION R2N29
J 0
(-425 2525);
DISPLAY 0.617021 (-425 2525);
PAINT AQUA (-425 2525);
FORCEPROP 1 LASTPIN (-275 2475) $PN 2
J 0
(-313 2487);
DISPLAY 0.617021 (-313 2487);
PAINT ORANGE (-313 2487);
FORCEPROP 1 LAST PART_NUMBER G21796-003
J 0
(-250 2425);
DISPLAY 0.617021 (-250 2425);
PAINT BLUE (-250 2425);
FORCEPROP 1 LAST MATERIAL CHIP
J 0
(0 2425);
DISPLAY 0.617021 (0 2425);
PAINT SKYBLUE (0 2425);
FORCEPROP 1 LAST WATTAGE 1/16W
J 2
(275 2425);
DISPLAY 0.617021 (275 2425);
PAINT SKYBLUE (275 2425);
FORCEPROP 1 LAST PACK_TYPE 0402
J 0
(300 2425);
DISPLAY 0.617021 (300 2425);
PAINT SKYBLUE (300 2425);
FORCEPROP 2 LAST BOM_COST SB
J 0
(-425 2325);
PAINT MONO (-425 2325);
DISPLAY INVISIBLE (-425 2325);
FORCEPROP 2 LAST CDS_LIB mstr_discrete
J 0
(-375 2475);
PAINT ORANGE (-375 2475);
DISPLAY INVISIBLE (-375 2475);
FORCEPROP 2 LAST ROOM SB
J 0
(-375 2475);
PAINT MONO (-375 2475);
DISPLAY INVISIBLE (-375 2475);
FORCEPROP 2 LAST SEC 1
J 0
(-425 2675);
DISPLAY 0.680851 (-425 2675);
PAINT MONO (-425 2675);
DISPLAY INVISIBLE (-425 2675);
FORCEPROP 2 LAST SEC_TYPE 0402
J 0
(-425 2675);
DISPLAY 1.021277 (-425 2675);
PAINT ORANGE (-425 2675);
DISPLAY INVISIBLE (-425 2675);
FORCEPROP 1 LAST PATH I352
J 0
(-425 2625);
DISPLAY 0.978723 (-425 2625);
PAINT WHITE (-425 2625);
DISPLAY INVISIBLE (-425 2625);
FORCEADD P3V3_STBY..1
(-625 2950);
FORCEPROP 3 LASTPIN (-625 2900) SIG_NAME P3V3_STBY\g
J 0
(-615 2910);
DISPLAY 0.659574 (-615 2910);
PAINT MONO (-615 2910);
DISPLAY INVISIBLE (-615 2910);
FORCEPROP 1 LAST HDL_POWER P3V3_STBY
J 0
(-925 2825);
DISPLAY 0.872340 (-925 2825);
PAINT ORANGE (-925 2825);
DISPLAY INVISIBLE (-925 2825);
FORCEPROP 1 LAST PATH I353
J 0
(-580 2952);
DISPLAY 0.340426 (-580 2952);
PAINT GREEN (-580 2952);
DISPLAY INVISIBLE (-580 2952);
FORCEPROP 1 LAST BODY_TYPE PLUMBING
J 0
(-670 2907);
DISPLAY 0.340426 (-670 2907);
PAINT GREEN (-670 2907);
DISPLAY INVISIBLE (-670 2907);
FORCEPROP 2 LAST CDS_LIB mstr_symbols
J 0
(-625 2950);
PAINT ORANGE (-625 2950);
DISPLAY INVISIBLE (-625 2950);
FORCEPROP 1 LAST SIZE 1B
J 0
(-580 2972);
DISPLAY 0.340426 (-580 2972);
PAINT GREEN (-580 2972);
DISPLAY INVISIBLE (-580 2972);
FORCEPROP 1 LAST VOLTAGE 3.3V
J 0
(-670 2907);
DISPLAY 0.340426 (-670 2907);
PAINT SKYBLUE (-670 2907);
DISPLAY INVISIBLE (-670 2907);
FORCEADD OFFPAGE..2
(-3850 3475);
FORCEPROP 2 LAST $XR0 249 
J 0
(-3661 3475);
DISPLAY 0.638298 (-3661 3475);
PAINT MONO (-3661 3475);
FORCEPROP 2 LAST $XR1 119 
J 0
(-3541 3475);
DISPLAY 0.638298 (-3541 3475);
PAINT MONO (-3541 3475);
FORCEPROP 2 LAST $XR2 147 
J 0
(-3541 3475);
DISPLAY 0.638298 (-3541 3475);
PAINT MONO (-3541 3475);
FORCEPROP 1 LAST COMMENT_BODY TRUE
J 0
(-3895 3380);
DISPLAY 0.872340 (-3895 3380);
PAINT GREEN (-3895 3380);
DISPLAY INVISIBLE (-3895 3380);
FORCEPROP 2 LAST CDS_LIB mstr_standard
J 0
(-3850 3475);
PAINT MONO (-3850 3475);
DISPLAY INVISIBLE (-3850 3475);
FORCEPROP 2 LAST PATH I354
J 0
(-3525 3525);
DISPLAY 1.021277 (-3525 3525);
PAINT ORANGE (-3525 3525);
DISPLAY INVISIBLE (-3525 3525);
FORCEPROP 1 LAST OFFPAGE TRUE
J 0
(-3525 3350);
DISPLAY 0.872340 (-3525 3350);
PAINT GREEN (-3525 3350);
DISPLAY INVISIBLE (-3525 3350);
FORCEADD RES..1
(-4700 3475);
FORCEPROP 1 LAST VALUE 10.0K
J 2
(-4725 3375);
DISPLAY 0.617021 (-4725 3375);
PAINT SKYBLUE (-4725 3375);
FORCEPROP 1 LASTPIN (-4800 3475) $PN 1
J 0
(-4788 3487);
DISPLAY 0.617021 (-4788 3487);
PAINT ORANGE (-4788 3487);
FORCEPROP 1 LAST LOCATION R8E3
J 0
(-4750 3525);
DISPLAY 0.617021 (-4750 3525);
PAINT AQUA (-4750 3525);
FORCEPROP 1 LASTPIN (-4600 3475) $PN 2
J 0
(-4638 3487);
DISPLAY 0.617021 (-4638 3487);
PAINT ORANGE (-4638 3487);
FORCEPROP 1 LAST TOLERANCE 1%
J 0
(-4700 3375);
DISPLAY 0.617021 (-4700 3375);
PAINT SKYBLUE (-4700 3375);
FORCEPROP 1 LAST WATTAGE 1/16W
J 2
(-4475 3375);
DISPLAY 0.617021 (-4475 3375);
PAINT SKYBLUE (-4475 3375);
FORCEPROP 1 LAST PACK_TYPE 0402
J 0
(-4325 3375);
DISPLAY 0.617021 (-4325 3375);
PAINT SKYBLUE (-4325 3375);
FORCEPROP 1 LAST MATERIAL CHIP
J 0
(-4450 3375);
DISPLAY 0.617021 (-4450 3375);
PAINT SKYBLUE (-4450 3375);
FORCEPROP 1 LAST PART_NUMBER G21796-016
J 0
(-4200 3375);
DISPLAY 0.617021 (-4200 3375);
PAINT BLUE (-4200 3375);
FORCEPROP 2 LAST CDS_LOCATION R8E3
J 0
(-4750 3525);
DISPLAY 0.617021 (-4750 3525);
PAINT AQUA (-4750 3525);
DISPLAY INVISIBLE (-4750 3525);
FORCEPROP 2 LAST CDS_LIB mstr_discrete
J 0
(-4700 3475);
PAINT MONO (-4700 3475);
DISPLAY INVISIBLE (-4700 3475);
FORCEPROP 1 LAST PATH I355
J 0
(-4750 3625);
DISPLAY 0.978723 (-4750 3625);
PAINT WHITE (-4750 3625);
DISPLAY INVISIBLE (-4750 3625);
FORCEPROP 2 LAST SEC 1
J 0
(-4750 3675);
DISPLAY 0.680851 (-4750 3675);
PAINT MONO (-4750 3675);
DISPLAY INVISIBLE (-4750 3675);
FORCEPROP 2 LAST SEC_TYPE 0402
J 0
(-4750 3675);
DISPLAY 1.021277 (-4750 3675);
PAINT ORANGE (-4750 3675);
DISPLAY INVISIBLE (-4750 3675);
FORCEPROP 0 LAST ROOM SB
J 0
(-4750 3625);
DISPLAY 1.021277 (-4750 3625);
PAINT ORANGE (-4750 3625);
DISPLAY INVISIBLE (-4750 3625);
FORCEADD RES..1
(-375 3725);
FORCEPROP 1 LAST VALUE 4.75K
J 2
(-475 3725);
DISPLAY 0.617021 (-475 3725);
PAINT SKYBLUE (-475 3725);
FORCEPROP 1 LAST WATTAGE 1/16W
J 2
(-450 3675);
DISPLAY 0.617021 (-450 3675);
PAINT SKYBLUE (-450 3675);
FORCEPROP 1 LASTPIN (-475 3725) $PN 1
J 0
(-463 3737);
DISPLAY 0.617021 (-463 3737);
PAINT ORANGE (-463 3737);
FORCEPROP 1 LAST LOCATION R7D44
J 0
(-425 3775);
DISPLAY 0.617021 (-425 3775);
PAINT AQUA (-425 3775);
FORCEPROP 1 LASTPIN (-275 3725) $PN 2
J 0
(-313 3737);
DISPLAY 0.617021 (-313 3737);
PAINT ORANGE (-313 3737);
FORCEPROP 1 LAST PART_NUMBER G21796-072
J 0
(-450 3675);
DISPLAY 0.617021 (-450 3675);
PAINT BLUE (-450 3675);
FORCEPROP 1 LAST TOLERANCE 1%
J 0
(-225 3675);
DISPLAY 0.617021 (-225 3675);
PAINT SKYBLUE (-225 3675);
FORCEPROP 1 LAST PACK_TYPE 0402
J 0
(-250 3725);
DISPLAY 0.617021 (-250 3725);
PAINT SKYBLUE (-250 3725);
FORCEPROP 1 LAST MATERIAL CHIP
J 0
(-150 3675);
DISPLAY 0.617021 (-150 3675);
PAINT SKYBLUE (-150 3675);
FORCEPROP 2 LAST CDS_LIB mstr_discrete
J 0
(-375 3725);
PAINT ORANGE (-375 3725);
DISPLAY INVISIBLE (-375 3725);
FORCEPROP 2 LAST ROOM SB_PU_PD
J 0
(-425 3825);
DISPLAY 1.021277 (-425 3825);
PAINT ORANGE (-425 3825);
DISPLAY INVISIBLE (-425 3825);
FORCEPROP 1 LAST PATH I356
J 0
(-425 3875);
DISPLAY 0.978723 (-425 3875);
PAINT WHITE (-425 3875);
DISPLAY INVISIBLE (-425 3875);
FORCEPROP 2 LAST SEC 1
J 0
(-425 3925);
DISPLAY 0.680851 (-425 3925);
PAINT MONO (-425 3925);
DISPLAY INVISIBLE (-425 3925);
FORCEPROP 2 LAST SEC_TYPE 0402
J 0
(-425 3925);
DISPLAY 1.021277 (-425 3925);
PAINT ORANGE (-425 3925);
DISPLAY INVISIBLE (-425 3925);
FORCEADD RES..1
(-375 3525);
FORCEPROP 1 LAST WATTAGE 1/16W
J 2
(-450 3475);
DISPLAY 0.617021 (-450 3475);
PAINT SKYBLUE (-450 3475);
FORCEPROP 1 LAST VALUE 4.75K
J 2
(-475 3525);
DISPLAY 0.617021 (-475 3525);
PAINT SKYBLUE (-475 3525);
FORCEPROP 1 LASTPIN (-475 3525) $PN 1
J 0
(-463 3537);
DISPLAY 0.617021 (-463 3537);
PAINT ORANGE (-463 3537);
FORCEPROP 1 LASTPIN (-275 3525) $PN 2
J 0
(-313 3537);
DISPLAY 0.617021 (-313 3537);
PAINT ORANGE (-313 3537);
FORCEPROP 1 LAST PART_NUMBER G21796-072
J 0
(-450 3475);
DISPLAY 0.617021 (-450 3475);
PAINT BLUE (-450 3475);
FORCEPROP 1 LAST TOLERANCE 1%
J 0
(-225 3475);
DISPLAY 0.617021 (-225 3475);
PAINT SKYBLUE (-225 3475);
FORCEPROP 1 LAST PACK_TYPE 0402
J 0
(-250 3525);
DISPLAY 0.617021 (-250 3525);
PAINT SKYBLUE (-250 3525);
FORCEPROP 1 LAST MATERIAL CHIP
J 0
(-150 3475);
DISPLAY 0.617021 (-150 3475);
PAINT SKYBLUE (-150 3475);
FORCEPROP 1 LAST LOCATION R3P53
J 0
(-425 3575);
DISPLAY 0.617021 (-425 3575);
PAINT AQUA (-425 3575);
FORCEPROP 2 LAST CDS_LIB mstr_discrete
J 0
(-375 3525);
PAINT ORANGE (-375 3525);
DISPLAY INVISIBLE (-375 3525);
FORCEPROP 1 LAST PATH I357
J 0
(-425 3675);
DISPLAY 0.978723 (-425 3675);
PAINT WHITE (-425 3675);
DISPLAY INVISIBLE (-425 3675);
FORCEPROP 2 LAST SEC 1
J 0
(-425 3725);
DISPLAY 0.680851 (-425 3725);
PAINT MONO (-425 3725);
DISPLAY INVISIBLE (-425 3725);
FORCEPROP 2 LAST SEC_TYPE 0402
J 0
(-425 3725);
DISPLAY 1.021277 (-425 3725);
PAINT ORANGE (-425 3725);
DISPLAY INVISIBLE (-425 3725);
FORCEPROP 2 LAST ROOM SB_PU_PD
J 0
(-425 3625);
DISPLAY 1.021277 (-425 3625);
PAINT ORANGE (-425 3625);
DISPLAY INVISIBLE (-425 3625);
FORCEADD OFFPAGE..2
(625 3725);
FORCEPROP 2 LAST $XR2 145 
J 0
(934 3725);
DISPLAY 0.638298 (934 3725);
PAINT MONO (934 3725);
FORCEPROP 2 LAST $XR0 187 
J 0
(814 3725);
DISPLAY 0.638298 (814 3725);
PAINT MONO (814 3725);
FORCEPROP 2 LAST $XR1 121 
J 0
(934 3725);
DISPLAY 0.638298 (934 3725);
PAINT MONO (934 3725);
FORCEPROP 1 LAST COMMENT_BODY TRUE
J 0
(580 3630);
DISPLAY 1.170213 (580 3630);
PAINT GREEN (580 3630);
DISPLAY INVISIBLE (580 3630);
FORCEPROP 2 LAST CDS_LIB mstr_standard
J 0
(625 3725);
PAINT ORANGE (625 3725);
DISPLAY INVISIBLE (625 3725);
FORCEPROP 2 LAST PATH I358
J 0
(800 3800);
DISPLAY 1.021277 (800 3800);
PAINT ORANGE (800 3800);
DISPLAY INVISIBLE (800 3800);
FORCEPROP 1 LAST OFFPAGE TRUE
J 0
(950 3600);
PAINT GREEN (950 3600);
DISPLAY INVISIBLE (950 3600);
FORCEPROP 2 LAST BOM_COST SB
J 0
(825 3775);
PAINT MONO (825 3775);
DISPLAY INVISIBLE (825 3775);
FORCEADD OFFPAGE..2
(625 3525);
FORCEPROP 2 LAST $XR2 145 
J 0
(934 3525);
DISPLAY 0.638298 (934 3525);
PAINT MONO (934 3525);
FORCEPROP 2 LAST $XR0 188 
J 0
(814 3525);
DISPLAY 0.638298 (814 3525);
PAINT MONO (814 3525);
FORCEPROP 2 LAST $XR1 121 
J 0
(934 3525);
DISPLAY 0.638298 (934 3525);
PAINT MONO (934 3525);
FORCEPROP 1 LAST COMMENT_BODY TRUE
J 0
(580 3430);
DISPLAY 1.170213 (580 3430);
PAINT GREEN (580 3430);
DISPLAY INVISIBLE (580 3430);
FORCEPROP 2 LAST CDS_LIB mstr_standard
J 0
(625 3525);
PAINT ORANGE (625 3525);
DISPLAY INVISIBLE (625 3525);
FORCEPROP 1 LAST OFFPAGE TRUE
J 0
(950 3400);
PAINT GREEN (950 3400);
DISPLAY INVISIBLE (950 3400);
FORCEPROP 2 LAST BOM_COST SB
J 0
(825 3575);
PAINT MONO (825 3575);
DISPLAY INVISIBLE (825 3575);
FORCEPROP 2 LAST PATH I359
J 0
(800 3600);
DISPLAY 1.021277 (800 3600);
PAINT ORANGE (800 3600);
DISPLAY INVISIBLE (800 3600);
FORCEADD RES..1
(-4800 1500);
FORCEPROP 1 LAST WATTAGE 1/16W
J 2
(-4870 1410);
DISPLAY 0.617021 (-4870 1410);
PAINT SKYBLUE (-4870 1410);
FORCEPROP 1 LAST VALUE 10.0K
J 2
(-4825 1450);
DISPLAY 0.617021 (-4825 1450);
PAINT SKYBLUE (-4825 1450);
FORCEPROP 1 LAST MATERIAL CHIP
J 0
(-4860 1410);
DISPLAY 0.617021 (-4860 1410);
PAINT SKYBLUE (-4860 1410);
FORCEPROP 1 LAST TOLERANCE 1%
J 0
(-4770 1450);
DISPLAY 0.617021 (-4770 1450);
PAINT SKYBLUE (-4770 1450);
FORCEPROP 1 LASTPIN (-4700 1500) $PN 2
J 0
(-4738 1512);
DISPLAY 0.617021 (-4738 1512);
PAINT ORANGE (-4738 1512);
FORCEPROP 1 LASTPIN (-4900 1500) $PN 1
J 0
(-4888 1512);
DISPLAY 0.617021 (-4888 1512);
PAINT ORANGE (-4888 1512);
FORCEPROP 1 LAST LOCATION R2P22
J 0
(-4950 1550);
DISPLAY 0.617021 (-4950 1550);
PAINT AQUA (-4950 1550);
FORCEPROP 1 LAST PART_NUMBER G21796-016
J 0
(-4725 1550);
DISPLAY 0.617021 (-4725 1550);
PAINT BLUE (-4725 1550);
FORCEPROP 1 LAST PACK_TYPE 0402
J 0
(-4690 1460);
DISPLAY 0.617021 (-4690 1460);
PAINT SKYBLUE (-4690 1460);
FORCEPROP 2 LAST BOM_COST SB
J 0
(-4850 1350);
PAINT MONO (-4850 1350);
DISPLAY INVISIBLE (-4850 1350);
FORCEPROP 2 LAST ROOM SB
J 0
(-4800 1500);
PAINT MONO (-4800 1500);
DISPLAY INVISIBLE (-4800 1500);
FORCEPROP 2 LAST CDS_LIB mstr_discrete
J 0
(-4800 1500);
PAINT ORANGE (-4800 1500);
DISPLAY INVISIBLE (-4800 1500);
FORCEPROP 1 LAST PATH I360
J 0
(-4850 1650);
DISPLAY 0.978723 (-4850 1650);
PAINT WHITE (-4850 1650);
DISPLAY INVISIBLE (-4850 1650);
FORCEPROP 2 LAST SEC 1
J 0
(-4850 1700);
DISPLAY 0.680851 (-4850 1700);
PAINT MONO (-4850 1700);
DISPLAY INVISIBLE (-4850 1700);
FORCEPROP 2 LAST SEC_TYPE 0402
J 0
(-4850 1700);
DISPLAY 1.021277 (-4850 1700);
PAINT ORANGE (-4850 1700);
DISPLAY INVISIBLE (-4850 1700);
FORCEADD OFFPAGE..2
(-3925 1500);
FORCEPROP 2 LAST $XR0 119 
J 0
(-3736 1500);
DISPLAY 0.638298 (-3736 1500);
PAINT MONO (-3736 1500);
FORCEPROP 2 LAST $XR1 190 
J 0
(-3616 1500);
DISPLAY 0.638298 (-3616 1500);
PAINT MONO (-3616 1500);
FORCEPROP 1 LAST COMMENT_BODY TRUE
J 0
(-3970 1405);
DISPLAY 1.170213 (-3970 1405);
PAINT GREEN (-3970 1405);
DISPLAY INVISIBLE (-3970 1405);
FORCEPROP 1 LAST OFFPAGE TRUE
J 0
(-3600 1375);
PAINT GREEN (-3600 1375);
DISPLAY INVISIBLE (-3600 1375);
FORCEPROP 2 LAST CDS_LIB mstr_standard
J 0
(-3925 1500);
PAINT ORANGE (-3925 1500);
DISPLAY INVISIBLE (-3925 1500);
FORCEPROP 2 LAST BOM_COST SB
J 0
(-3725 1550);
PAINT MONO (-3725 1550);
DISPLAY INVISIBLE (-3725 1550);
FORCEPROP 2 LAST PATH I361
J 0
(-3750 1575);
DISPLAY 1.021277 (-3750 1575);
PAINT ORANGE (-3750 1575);
DISPLAY INVISIBLE (-3750 1575);
FORCEADD RES..1
(-2475 2450);
FORCEPROP 1 LAST WATTAGE 1/16W
J 2
(-2545 2360);
DISPLAY 0.617021 (-2545 2360);
PAINT SKYBLUE (-2545 2360);
FORCEPROP 1 LAST VALUE 10.0K
J 2
(-2500 2400);
DISPLAY 0.617021 (-2500 2400);
PAINT SKYBLUE (-2500 2400);
FORCEPROP 1 LASTPIN (-2575 2450) $PN 1
J 0
(-2563 2462);
DISPLAY 0.617021 (-2563 2462);
PAINT ORANGE (-2563 2462);
FORCEPROP 1 LAST LOCATION R8D44
J 0
(-2525 2500);
DISPLAY 0.617021 (-2525 2500);
PAINT AQUA (-2525 2500);
FORCEPROP 1 LAST TOLERANCE 1%
J 0
(-2445 2400);
DISPLAY 0.617021 (-2445 2400);
PAINT SKYBLUE (-2445 2400);
FORCEPROP 1 LAST MATERIAL CHIP
J 0
(-2535 2360);
DISPLAY 0.617021 (-2535 2360);
PAINT SKYBLUE (-2535 2360);
FORCEPROP 1 LASTPIN (-2375 2450) $PN 2
J 0
(-2413 2462);
DISPLAY 0.617021 (-2413 2462);
PAINT ORANGE (-2413 2462);
FORCEPROP 1 LAST PACK_TYPE 0402
J 0
(-2365 2410);
DISPLAY 0.617021 (-2365 2410);
PAINT SKYBLUE (-2365 2410);
FORCEPROP 1 LAST PART_NUMBER G21796-016
J 0
(-2400 2500);
DISPLAY 0.617021 (-2400 2500);
PAINT BLUE (-2400 2500);
FORCEPROP 2 LAST BOM_COST SB
J 0
(-2525 2300);
PAINT MONO (-2525 2300);
DISPLAY INVISIBLE (-2525 2300);
FORCEPROP 2 LAST CDS_LIB mstr_discrete
J 0
(-2475 2450);
PAINT ORANGE (-2475 2450);
DISPLAY INVISIBLE (-2475 2450);
FORCEPROP 2 LAST ROOM SB
J 0
(-2475 2450);
PAINT MONO (-2475 2450);
DISPLAY INVISIBLE (-2475 2450);
FORCEPROP 1 LAST PATH I362
J 0
(-2525 2600);
DISPLAY 0.978723 (-2525 2600);
PAINT WHITE (-2525 2600);
DISPLAY INVISIBLE (-2525 2600);
FORCEPROP 2 LAST SEC 1
J 0
(-2525 2650);
DISPLAY 0.680851 (-2525 2650);
PAINT MONO (-2525 2650);
DISPLAY INVISIBLE (-2525 2650);
FORCEPROP 2 LAST SEC_TYPE 0402
J 0
(-2525 2650);
DISPLAY 1.021277 (-2525 2650);
PAINT ORANGE (-2525 2650);
DISPLAY INVISIBLE (-2525 2650);
FORCEADD OFFPAGE..2
(-1575 2450);
FORCEPROP 2 LAST $XR0 120 
J 0
(-1386 2450);
DISPLAY 0.638298 (-1386 2450);
PAINT MONO (-1386 2450);
FORCEPROP 2 LAST $XR1 190 
J 0
(-1266 2450);
DISPLAY 0.638298 (-1266 2450);
PAINT MONO (-1266 2450);
FORCEPROP 1 LAST COMMENT_BODY TRUE
J 0
(-1620 2355);
DISPLAY 1.170213 (-1620 2355);
PAINT GREEN (-1620 2355);
DISPLAY INVISIBLE (-1620 2355);
FORCEPROP 2 LAST CDS_LIB mstr_standard
J 0
(-1575 2450);
PAINT ORANGE (-1575 2450);
DISPLAY INVISIBLE (-1575 2450);
FORCEPROP 2 LAST BOM_COST SB
J 0
(-1375 2500);
PAINT MONO (-1375 2500);
DISPLAY INVISIBLE (-1375 2500);
FORCEPROP 1 LAST OFFPAGE TRUE
J 0
(-1250 2325);
PAINT GREEN (-1250 2325);
DISPLAY INVISIBLE (-1250 2325);
FORCEPROP 2 LAST PATH I363
J 0
(-1400 2525);
DISPLAY 1.021277 (-1400 2525);
PAINT ORANGE (-1400 2525);
DISPLAY INVISIBLE (-1400 2525);
FORCEADD INTEL_CORP_BPAGE..1
(2650 500);
FORCEPROP 1 LAST CDS_CON_LAST_MODIFIED Tue Dec 01 11:52:01 2015
J 0
(1225 825);
PAINT ORANGE (1225 825);
DISPLAY INVISIBLE (1225 825);
FORCEPROP 1 LAST CUSTOM_TXT_CDS <CURRENT_DESIGN_SHEET> OF <TOTAL_DESIGN_SHEETS>
J 0
(2150 525);
PAINT GREEN (2150 525);
FORCEPROP 1 LAST CUSTOM_TXT_CDS <CON_LAST_MODIFIED>
J 0
(725 850);
PAINT GREEN (725 850);
FORCEPROP 2 LAST CUSTOM_TXT_CDS <XR_PAGE_TITLE>
J 0
(-5240 5750);
DISPLAY 0.638298 (-5240 5750);
PAINT PINK (-5240 5750);
DISPLAY INVISIBLE (-5240 5750);
FORCEPROP 1 LAST SCH_TITLE LBG PULLUPS/PULLDOWNS
J 0
(-5300 550);
DISPLAY 1.212766 (-5300 550);
PAINT ORANGE (-5300 550);
FORCEPROP 1 LAST SCH_ADDRESS3 Santa Clara, CA 95052-8119
J 0
(-1325 525);
DISPLAY 0.617021 (-1325 525);
PAINT GREEN (-1325 525);
FORCEPROP 1 LAST SCH_ADDRESS2 P.O. BOX 58119
J 0
(-1325 575);
DISPLAY 0.617021 (-1325 575);
PAINT GREEN (-1325 575);
FORCEPROP 1 LAST SCH_ADDRESS1 2200 Mission College Blvd.
J 0
(-1325 625);
DISPLAY 0.617021 (-1325 625);
PAINT GREEN (-1325 625);
FORCEPROP 1 LAST SCH_NUMBER H4694802
J 0
(1350 650);
DISPLAY 1.212766 (1350 650);
PAINT YELLOW (1350 650);
FORCEPROP 1 LAST SCH_DEPT BESD
J 1
(-1800 600);
DISPLAY 1.212766 (-1800 600);
PAINT YELLOW (-1800 600);
FORCEPROP 1 LAST SCH_REV 2.420
J 0
(2400 650);
DISPLAY 0.978723 (2400 650);
PAINT YELLOW (2400 650);
FORCEPROP 2 LAST PAGE_BORDER TRUE
J 0
(-5240 5750);
DISPLAY 0.851064 (-5240 5750);
PAINT PINK (-5240 5750);
DISPLAY INVISIBLE (-5240 5750);
FORCEPROP 2 LAST BOM_COST SB
J 0
(-5225 5800);
PAINT MONO (-5225 5800);
DISPLAY INVISIBLE (-5225 5800);
FORCEPROP 1 LAST COMMENT_BODY TRUE
J 0
(2662 512);
DISPLAY 0.468085 (2662 512);
PAINT GREEN (2662 512);
DISPLAY INVISIBLE (2662 512);
FORCEPROP 2 LAST CDS_LIB mstr_symbols
J 0
(2650 500);
PAINT MONO (2650 500);
DISPLAY INVISIBLE (2650 500);
FORCEPROP 2 LAST CDS_XR_PAGE_TITLE CR-133 : @BASEBOARD_FAB2_LIB.BASEBOARD_FAB2(SCH_1):PAGE133
J 0
(-5240 5750);
DISPLAY 0.638298 (-5240 5750);
PAINT PINK (-5240 5750);
DISPLAY INVISIBLE (-5240 5750);
FORCEADD DNS..2
(-2495 4070);
PAINT RED (-2495 4070);
FORCEPROP 1 LAST COMMENT_BODY TRUE
R 1
J 0
(-2420 3845);
DISPLAY 0.872340 (-2420 3845);
PAINT GREEN (-2420 3845);
DISPLAY INVISIBLE (-2420 3845);
FORCEPROP 2 LAST CDS_LIB mstr_misc
J 0
(-2495 4070);
PAINT ORANGE (-2495 4070);
DISPLAY INVISIBLE (-2495 4070);
FORCEADD DESIGN_NOTE..1
(-400 3300);
FORCEPROP 0 LAST L1 GPIO L FAMILY IS ON P1V05_PCH_STBY
J 0
(-600 3175);
DISPLAY 0.808511 (-600 3175);
PAINT ORANGE (-600 3175);
FORCEPROP 2 LAST CDS_LIB mstr_symbols
J 0
(-400 3300);
PAINT ORANGE (-400 3300);
DISPLAY INVISIBLE (-400 3300);
FORCEPROP 1 LAST COMMENT_BODY TRUE
J 0
(-375 3400);
DISPLAY 0.978723 (-375 3400);
PAINT ORANGE (-375 3400);
DISPLAY INVISIBLE (-375 3400);
WIRE 16 -1 (-2600 4075)(-2825 4075);
WIRE 16 -1 (-2825 3850)(-2825 4075);
WIRE 16 -1 (-2600 3850)(-2825 3850);
WIRE 16 -1 (-2825 3650)(-2825 3850);
WIRE 16 -1 (-4950 2400)(-4950 2725);
WIRE 16 -1 (-4950 2400)(-4775 2400);
WIRE 16 -1 (-4950 2725)(-4750 2725);
WIRE 16 -1 (-4950 2725)(-4950 2875);
WIRE 16 -1 (-4900 950)(-5075 950);
WIRE 16 -1 (-5075 950)(-5075 1125);
WIRE 16 -1 (-4900 1125)(-5075 1125);
WIRE 16 -1 (-5075 1125)(-5075 1300);
WIRE 16 -1 (-5075 1300)(-4900 1300);
WIRE 16 -1 (-5075 1300)(-5075 1500);
WIRE 16 -1 (-4900 1500)(-5075 1500);
WIRE 16 -1 (-5075 1500)(-5075 1650);
WIRE 16 -1 (-5075 1825)(-5075 1650);
WIRE 16 -1 (-5075 1650)(-4900 1650);
WIRE 16 -1 (-5075 1825)(-4900 1825);
WIRE 16 -1 (-5075 1825)(-5075 1925);
WIRE 16 -1 (-2675 4425)(-2825 4425);
WIRE 16 -1 (-2825 4675)(-2825 4425);
WIRE 16 -1 (-2675 4675)(-2825 4675);
WIRE 16 -1 (-2825 4675)(-2825 4900);
WIRE 16 -1 (-2700 4900)(-2825 4900);
WIRE 16 -1 (-2825 4900)(-2825 5125);
WIRE 16 -1 (-2700 5125)(-2825 5125);
WIRE 16 -1 (-2825 5300)(-2825 5125);
WIRE 16 -1 (-2750 1025)(-2575 1025);
WIRE 16 -1 (-2750 1025)(-2750 1275);
WIRE 16 -1 (-2750 1375)(-2750 1275);
WIRE 16 -1 (-2750 1275)(-2575 1275);
WIRE 16 -1 (-175 1525)(-175 1700);
WIRE 16 -1 (-175 1700)(-425 1700);
WIRE 16 -1 (-425 1525)(-425 1700);
WIRE 16 -1 (-425 1700)(-650 1700);
WIRE 16 -1 (-650 1525)(-650 1700);
WIRE 16 -1 (-650 1800)(-650 1700);
WIRE 16 -1 (-2800 1800)(-2575 1800);
WIRE 16 -1 (-2800 2000)(-2800 1800);
WIRE 16 -1 (-4950 3700)(-4950 3475);
WIRE 16 -1 (-4950 3700)(-4800 3700);
WIRE 16 -1 (-4950 3700)(-4950 3925);
WIRE 16 -1 (-4950 3475)(-4800 3475);
WIRE 16 -1 (-4950 4125)(-4950 3925);
WIRE 16 -1 (-4950 3925)(-4800 3925);
WIRE 16 -1 (-4950 4125)(-4800 4125);
WIRE 16 -1 (-4950 4125)(-4950 4325);
WIRE 16 -1 (-4950 4325)(-4800 4325);
WIRE 16 -1 (-4950 4325)(-4950 4500);
WIRE 16 -1 (-4950 4500)(-4950 4700);
WIRE 16 -1 (-4950 4500)(-4800 4500);
WIRE 16 -1 (-4950 4700)(-4800 4700);
WIRE 16 -1 (-4950 4900)(-4950 4700);
WIRE 16 -1 (-4950 4900)(-4800 4900);
WIRE 16 -1 (-4950 5100)(-4950 4900);
WIRE 16 -1 (-4950 5100)(-4950 5175);
WIRE 16 -1 (-4950 5100)(-4800 5100);
WIRE 16 -1 (-2775 3150)(-2600 3150);
WIRE 16 -1 (-2775 3150)(-2775 3375);
WIRE 16 -1 (-625 3525)(-475 3525);
WIRE 16 -1 (-625 3725)(-625 3525);
WIRE 16 -1 (-625 3725)(-475 3725);
WIRE 16 -1 (-625 3925)(-625 3725);
WIRE 16 -1 (-475 3925)(-625 3925);
WIRE 16 -1 (-625 4175)(-625 3925);
WIRE 16 -1 (-475 4175)(-625 4175);
WIRE 16 -1 (-625 4175)(-625 4400);
WIRE 16 -1 (-475 4400)(-625 4400);
WIRE 16 -1 (-625 4650)(-625 4400);
WIRE 16 -1 (-475 4650)(-625 4650);
WIRE 16 -1 (-625 4650)(-625 4875);
WIRE 16 -1 (-500 4875)(-625 4875);
WIRE 16 -1 (-625 4875)(-625 5100);
WIRE 16 -1 (-500 5100)(-625 5100);
WIRE 16 -1 (-625 5275)(-625 5100);
WIRE 16 -1 (-2575 2450)(-2800 2450);
WIRE 16 -1 (-2800 2450)(-2800 2700);
WIRE 16 -1 (-2800 2825)(-2800 2700);
WIRE 16 -1 (-2800 2700)(-2575 2700);
WIRE 16 -1 (-625 2475)(-475 2475);
WIRE 16 -1 (-625 2475)(-625 2725);
WIRE 16 -1 (-625 2725)(-475 2725);
WIRE 16 -1 (-625 2900)(-625 2725);
WIRE 16 273 (1225 5425)(1225 2275);
WIRE 16 -1 (2450 1950)(2450 2050);
WIRE 16 -1 (2450 1850)(2450 1950);
WIRE 16 -1 (75 1950)(2450 1950);
WIRE 16 -1 (2450 2050)(1775 2050);
WIRE 16 -1 (1775 2050)(1275 2050);
WIRE 16 -1 (1775 2050)(1775 1450);
WIRE 16 -1 (75 2050)(75 1950);
WIRE 16 -1 (75 1950)(75 1850);
WIRE 16 -1 (2450 1750)(2450 1850);
WIRE 16 -1 (75 1850)(2450 1850);
WIRE 16 -1 (75 1850)(75 1750);
WIRE 16 -1 (2450 1650)(2450 1750);
WIRE 16 -1 (75 1750)(2450 1750);
WIRE 16 -1 (800 2050)(75 2050);
WIRE 16 -1 (2450 1450)(1775 1450);
WIRE 16 -1 (1775 1450)(1275 1450);
WIRE 16 -1 (1275 2050)(800 2050);
WIRE 16 -1 (1275 2050)(1275 1450);
WIRE 16 -1 (800 1450)(1275 1450);
WIRE 16 -1 (800 2050)(800 1450);
WIRE 16 -1 (2450 1550)(2450 1450);
WIRE 16 -1 (75 1750)(75 1650);
WIRE 16 -1 (2450 1550)(2450 1650);
WIRE 16 -1 (75 1650)(2450 1650);
WIRE 16 -1 (75 1650)(75 1550);
WIRE 16 -1 (75 1550)(2450 1550);
WIRE 16 -1 (75 1450)(800 1450);
WIRE 16 -1 (75 1550)(75 1450);
WIRE 16 273 (-950 4275)(-950 5475);
WIRE 16 273 (-3050 4275)(-950 4275);
WIRE 16 273 (-950 3550)(-950 4275);
WIRE 16 273 (-950 3125)(-950 3550);
WIRE 16 273 (-3050 3550)(-950 3550);
WIRE 16 273 (-3050 5500)(-3050 4275);
WIRE 16 273 (-3050 4275)(-3050 3550);
WIRE 16 273 (-3050 3550)(-3050 3100);
WIRE 16 273 (-950 3125)(1150 3125);
WIRE 16 273 (-950 3000)(-950 3125);
WIRE 16 273 (-950 2275)(-950 3000);
WIRE 16 273 (-3050 3000)(-950 3000);
WIRE 16 273 (-3050 3000)(-3050 3100);
WIRE 16 273 (-5275 3100)(-3050 3100);
WIRE 16 273 (-3050 2275)(-3050 3000);
WIRE 16 273 (-950 900)(-950 2275);
WIRE 16 273 (-3050 2275)(-950 2275);
WIRE 16 273 (-3050 2275)(-3050 2125);
WIRE 16 273 (-3050 1525)(-3050 2125);
WIRE 16 273 (-5200 2125)(-3050 2125);
WIRE 16 273 (-3050 1525)(-975 1525);
WIRE 16 273 (-3050 725)(-3050 1525);
WIRE 16 273 (-800 2250)(2550 2250);
WIRE 16 -1 (1325 1075)(-425 1075);
FORCEPROP 0 LAST SIG_NAME FM_WBG_PRSNT_N
J 0
(440 1085);
DISPLAY 0.617021 (440 1085);
PAINT ORANGE (440 1085);
WIRE 16 -1 (-425 1075)(-425 1325);
WIRE 16 -1 (-650 1000)(1325 1000);
FORCEPROP 0 LAST SIG_NAME FM_SINT_PRSNT_N
J 0
(440 1010);
DISPLAY 0.617021 (440 1010);
PAINT ORANGE (440 1010);
WIRE 16 -1 (-650 1325)(-650 1000);
WIRE 16 -1 (-175 1150)(1325 1150);
FORCEPROP 0 LAST SIG_NAME FM_PCH_PRSNT_N
J 0
(440 1160);
DISPLAY 0.617021 (440 1160);
PAINT ORANGE (440 1160);
WIRE 16 -1 (-175 1325)(-175 1150);
WIRE 16 -1 (-300 5100)(575 5100);
FORCEPROP 2 LAST SIG_NAME FM_PRSNT_2_1_N
J 0
(15 5110);
DISPLAY 0.617021 (15 5110);
PAINT ORANGE (15 5110);
WIRE 16 -1 (-300 4875)(575 4875);
FORCEPROP 2 LAST SIG_NAME FM_PRSNT_2_2_N
J 0
(15 4885);
DISPLAY 0.617021 (15 4885);
PAINT ORANGE (15 4885);
WIRE 16 -1 (-275 4650)(575 4650);
FORCEPROP 2 LAST SIG_NAME FM_PRSNT_2_3_N
J 0
(15 4660);
DISPLAY 0.617021 (15 4660);
PAINT ORANGE (15 4660);
WIRE 16 -1 (-275 4400)(575 4400);
FORCEPROP 2 LAST SIG_NAME FM_PRSNT_2_4_N
J 0
(15 4410);
DISPLAY 0.617021 (15 4410);
PAINT ORANGE (15 4410);
WIRE 16 -1 (-275 4175)(575 4175);
FORCEPROP 2 LAST SIG_NAME FM_PRSNT_2_5_N
J 0
(15 4185);
DISPLAY 0.617021 (15 4185);
PAINT ORANGE (15 4185);
WIRE 16 -1 (-275 3925)(575 3925);
FORCEPROP 2 LAST SIG_NAME FM_PRSNT_2_6_N
J 0
(0 3935);
DISPLAY 0.617021 (0 3935);
PAINT ORANGE (0 3935);
WIRE 16 -1 (-275 2725)(575 2725);
FORCEPROP 2 LAST SIG_NAME FM_CPU0_RC_ERROR_N
J 0
(15 2735);
DISPLAY 0.617021 (15 2735);
PAINT ORANGE (15 2735);
WIRE 16 -1 (-275 2475)(575 2475);
FORCEPROP 2 LAST SIG_NAME FM_CPU1_RC_ERROR_N
J 0
(15 2485);
DISPLAY 0.617021 (15 2485);
PAINT ORANGE (15 2485);
WIRE 16 -1 (-275 3725)(575 3725);
FORCEPROP 2 LAST SIG_NAME FM_OCP_MEZZB_PRES_N
J 0
(-60 3735);
DISPLAY 0.617021 (-60 3735);
PAINT ORANGE (-60 3735);
WIRE 16 -1 (-275 3525)(575 3525);
FORCEPROP 2 LAST SIG_NAME FM_OCP_MEZZC_PRES_N
J 0
(-10 3535);
DISPLAY 0.617021 (-10 3535);
PAINT ORANGE (-10 3535);
WIRE 16 -1 (-2500 5125)(-1750 5125);
FORCEPROP 0 LAST SIG_NAME FM_PCH_PLD_DATA
J 0
(-2135 5135);
DISPLAY 0.617021 (-2135 5135);
PAINT ORANGE (-2135 5135);
WIRE 16 -1 (-2475 4675)(-1725 4675);
FORCEPROP 0 LAST SIG_NAME FM_XRC_PRESENT_N
J 0
(-2110 4685);
DISPLAY 0.617021 (-2110 4685);
PAINT ORANGE (-2110 4685);
WIRE 16 -1 (-2475 4425)(-1725 4425);
FORCEPROP 0 LAST SIG_NAME FM_XRC_READY_N
J 0
(-2110 4435);
DISPLAY 0.617021 (-2110 4435);
PAINT ORANGE (-2110 4435);
WIRE 16 -1 (-2500 4900)(-1750 4900);
FORCEPROP 0 LAST SIG_NAME IRQ_HSC_FAULT_N
J 0
(-2135 4910);
DISPLAY 0.617021 (-2135 4910);
PAINT ORANGE (-2135 4910);
WIRE 16 -1 (-2400 3150)(-1650 3150);
FORCEPROP 0 LAST SIG_NAME IRQ_PCH_NIC_ALERT_N
J 0
(-2175 3160);
DISPLAY 0.617021 (-2175 3160);
PAINT ORANGE (-2175 3160);
WIRE 16 -1 (-2375 2700)(-1625 2700);
FORCEPROP 0 LAST SIG_NAME FM_BIOS_SMI_ACTIVE_N
J 0
(-2175 2710);
DISPLAY 0.617021 (-2175 2710);
PAINT ORANGE (-2175 2710);
WIRE 16 -1 (-2375 2450)(-1625 2450);
FORCEPROP 0 LAST SIG_NAME FM_CPU0_RC_EN
J 0
(-2175 2460);
DISPLAY 0.617021 (-2175 2460);
PAINT ORANGE (-2175 2460);
WIRE 16 -1 (-2375 1800)(-1625 1800);
FORCEPROP 0 LAST SIG_NAME FP_PWR_ID_LED_N
J 0
(-2250 1810);
DISPLAY 0.617021 (-2250 1810);
PAINT ORANGE (-2250 1810);
WIRE 16 -1 (-2375 1025)(-1700 1025);
FORCEPROP 0 LAST SIG_NAME IRQ_BOARD_BMC_ALERT_N
J 0
(-2250 1035);
DISPLAY 0.617021 (-2250 1035);
PAINT ORANGE (-2250 1035);
WIRE 16 -1 (-2375 1275)(-1700 1275);
FORCEPROP 2 LAST SIG_NAME PU_10GBE_LOM_PCI_DISABLE_N
J 0
(-2250 1285);
DISPLAY 0.617021 (-2250 1285);
PAINT ORANGE (-2250 1285);
WIRE 16 -1 (-2400 4075)(-1650 4075);
FORCEPROP 2 LAST SIG_NAME PWRGD_SYS_PWROK
J 2
(-1735 4085);
DISPLAY 0.617021 (-1735 4085);
PAINT ORANGE (-1735 4085);
WIRE 16 -1 (-2400 3850)(-1650 3850);
FORCEPROP 2 LAST SIG_NAME PWRGD_PCH_PWROK
J 2
(-1735 3860);
DISPLAY 0.617021 (-1735 3860);
PAINT ORANGE (-1735 3860);
WIRE 16 -1 (-4600 3475)(-3900 3475);
FORCEPROP 2 LAST SIG_NAME FM_TPM_PRES_N
J 0
(-4425 3485);
DISPLAY 0.617021 (-4425 3485);
PAINT ORANGE (-4425 3485);
WIRE 16 -1 (-4600 4325)(-3900 4325);
FORCEPROP 0 LAST SIG_NAME PU_LPC_PME_N
J 0
(-4435 4335);
DISPLAY 0.617021 (-4435 4335);
PAINT ORANGE (-4435 4335);
WIRE 16 -1 (-4600 4125)(-3900 4125);
FORCEPROP 0 LAST SIG_NAME PU_IRQ_PCH_SCI_WHEA_N
J 0
(-4435 4135);
DISPLAY 0.617021 (-4435 4135);
PAINT ORANGE (-4435 4135);
WIRE 16 -1 (-4600 3925)(-3900 3925);
FORCEPROP 2 LAST SIG_NAME FM_OCP_MEZZA_PRES_N
J 0
(-4435 3935);
DISPLAY 0.617021 (-4435 3935);
PAINT ORANGE (-4435 3935);
WIRE 16 -1 (-4700 1300)(-3975 1300);
FORCEPROP 2 LAST SIG_NAME FM_SLT_CFG1
J 0
(-4475 1310);
DISPLAY 0.617021 (-4475 1310);
PAINT ORANGE (-4475 1310);
WIRE 16 -1 (-4700 950)(-3975 950);
FORCEPROP 0 LAST SIG_NAME IRQ_BMC_PCH_SMI_LPC_N
J 0
(-4475 960);
DISPLAY 0.617021 (-4475 960);
PAINT ORANGE (-4475 960);
WIRE 16 -1 (-4700 1125)(-3975 1125);
FORCEPROP 2 LAST SIG_NAME FM_SLT_CFG0
J 0
(-4475 1135);
DISPLAY 0.617021 (-4475 1135);
PAINT ORANGE (-4475 1135);
WIRE 16 -1 (-4700 1500)(-3975 1500);
FORCEPROP 0 LAST SIG_NAME FM_CPU1_RC_EN
J 0
(-4475 1510);
DISPLAY 0.617021 (-4475 1510);
PAINT ORANGE (-4475 1510);
WIRE 16 -1 (-4700 1650)(-3975 1650);
FORCEPROP 0 LAST SIG_NAME FM_THROTTLE_N
J 0
(-4475 1660);
DISPLAY 0.617021 (-4475 1660);
PAINT ORANGE (-4475 1660);
WIRE 16 -1 (-4700 1825)(-3975 1825);
FORCEPROP 2 LAST SIG_NAME IRQ_BMC_PCH_SCI_LPC_N
J 0
(-4475 1835);
DISPLAY 0.617021 (-4475 1835);
PAINT ORANGE (-4475 1835);
WIRE 16 -1 (-4600 5100)(-3900 5100);
WIRE 16 -1 (-4600 4700)(-3900 4700);
FORCEPROP 0 LAST SIG_NAME IRQ_PIRQA_SPI_TPM_N
J 0
(-4435 4710);
DISPLAY 0.617021 (-4435 4710);
PAINT ORANGE (-4435 4710);
WIRE 16 -1 (-4600 3700)(-3900 3700);
FORCEPROP 2 LAST SIG_NAME FM_BMC_READY_N
J 0
(-4425 3710);
DISPLAY 0.617021 (-4425 3710);
PAINT ORANGE (-4425 3710);
WIRE 16 -1 (-4600 4900)(-3900 4900);
FORCEPROP 0 LAST SIG_NAME IRQ_LPC_SERIRQ_N
J 0
(-4435 4910);
DISPLAY 0.617021 (-4435 4910);
PAINT ORANGE (-4435 4910);
WIRE 16 -1 (-4550 2725)(-3750 2725);
FORCEPROP 2 LAST SIG_NAME PU_IRQ_VRALERT_N
J 0
(-4235 2735);
DISPLAY 0.617021 (-4235 2735);
PAINT ORANGE (-4235 2735);
WIRE 16 -1 (-4575 2400)(-3750 2400);
FORCEPROP 0 LAST SIG_NAME FM_BIOS_POST_CMPLT_N
J 0
(-4235 2410);
DISPLAY 0.617021 (-4235 2410);
PAINT ORANGE (-4235 2410);
WIRE 16 -1 (-4600 4500)(-3900 4500);
FORCEPROP 0 LAST SIG_NAME PU_LPC_CLKRUN_N
J 0
(-4435 4510);
DISPLAY 0.617021 (-4435 4510);
PAINT ORANGE (-4435 4510);
DOT 1 (2450 1850);
DOT 1 (2450 1950);
DOT 1 (2450 1750);
DOT 1 (2450 1650);
DOT 1 (2450 1550);
DOT 1 (800 2050);
DOT 1 (1275 2050);
DOT 1 (1775 2050);
DOT 1 (1775 1450);
DOT 1 (1275 1450);
DOT 1 (800 1450);
DOT 1 (75 1950);
DOT 1 (75 1850);
DOT 1 (75 1750);
DOT 1 (75 1650);
DOT 1 (75 1550);
DOT 1 (-625 5100);
DOT 1 (-625 4875);
DOT 1 (-625 4650);
DOT 1 (-625 4175);
DOT 1 (-625 4400);
DOT 1 (-950 4275);
DOT 1 (-2825 5125);
DOT 1 (-2825 4675);
DOT 1 (-2825 4900);
DOT 1 (-3050 4275);
DOT 1 (-625 3925);
DOT 1 (-625 3725);
DOT 1 (-950 3125);
DOT 1 (-950 3550);
DOT 1 (-625 2725);
DOT 1 (-950 3000);
DOT 1 (-950 2275);
DOT 1 (-425 1700);
DOT 1 (-650 1700);
DOT 1 (-2825 3850);
DOT 1 (-3050 3550);
DOT 1 (-3050 3100);
DOT 1 (-2800 2700);
DOT 1 (-3050 3000);
DOT 1 (-3050 2275);
DOT 1 (-3050 2125);
DOT 1 (-2750 1275);
DOT 1 (-3050 1525);
DOT 1 (-4950 5100);
DOT 1 (-4950 4900);
DOT 1 (-4950 4700);
DOT 1 (-4950 4500);
DOT 1 (-4950 4325);
DOT 1 (-4950 4125);
DOT 1 (-4950 3925);
DOT 1 (-4950 3700);
DOT 1 (-4950 2725);
DOT 1 (-5075 1825);
DOT 1 (-5075 1650);
DOT 1 (-5075 1500);
DOT 1 (-5075 1300);
DOT 1 (-5075 1125);
FORCENOTE
GPP_L
(825 5325) 0;
DISPLAY LEFT (825 5325);
DISPLAY 1.021277 (825 5325);
PAINT PURPLE (825 5325);
FORCENOTE
WBG
(2000 1675) 0;
DISPLAY LEFT (2000 1675);
DISPLAY 0.808511 (2000 1675);
PAINT PURPLE (2000 1675);
FORCENOTE
RSVD
(2000 1775) 0;
DISPLAY LEFT (2000 1775);
DISPLAY 0.808511 (2000 1775);
PAINT PURPLE (2000 1775);
FORCENOTE
COMMENT
(1900 1975) 0;
DISPLAY LEFT (1900 1975);
DISPLAY 1.021277 (1900 1975);
PAINT PURPLE (1900 1975);
FORCENOTE
INSTALLED WRONG DIRECTION
(1825 1475) 0;
DISPLAY LEFT (1825 1475);
DISPLAY 0.638298 (1825 1475);
PAINT PURPLE (1825 1475);
FORCENOTE
LBG
(2000 1575) 0;
DISPLAY LEFT (2000 1575);
DISPLAY 0.808511 (2000 1575);
PAINT PURPLE (2000 1575);
FORCENOTE
PCH DETECTION
(100 2075) 0;
DISPLAY LEFT (100 2075);
DISPLAY 1.276596 (100 2075);
PAINT PURPLE (100 2075);
FORCENOTE
PIN D8
(1400 1975) 0;
DISPLAY LEFT (1400 1975);
DISPLAY 1.021277 (1400 1975);
PAINT PURPLE (1400 1975);
FORCENOTE
0
(1500 1675) 0;
DISPLAY LEFT (1500 1675);
DISPLAY 1.021277 (1500 1675);
PAINT PURPLE (1500 1675);
FORCENOTE
1
(1500 1575) 0;
DISPLAY LEFT (1500 1575);
DISPLAY 1.021277 (1500 1575);
PAINT PURPLE (1500 1575);
FORCENOTE
X
(1500 1475) 0;
DISPLAY LEFT (1500 1475);
DISPLAY 1.021277 (1500 1475);
PAINT PURPLE (1500 1475);
FORCENOTE
1
(1500 1775) 0;
DISPLAY LEFT (1500 1775);
DISPLAY 1.021277 (1500 1775);
PAINT PURPLE (1500 1775);
FORCENOTE
WBG_PRSNT
(1350 1875) 0;
DISPLAY LEFT (1350 1875);
DISPLAY 1.021277 (1350 1875);
PAINT PURPLE (1350 1875);
FORCENOTE
0
(1025 1775) 0;
DISPLAY LEFT (1025 1775);
DISPLAY 1.021277 (1025 1775);
PAINT PURPLE (1025 1775);
FORCENOTE
1
(1025 1675) 0;
DISPLAY LEFT (1025 1675);
DISPLAY 1.021277 (1025 1675);
PAINT PURPLE (1025 1675);
FORCENOTE
1
(1025 1575) 0;
DISPLAY LEFT (1025 1575);
DISPLAY 1.021277 (1025 1575);
PAINT PURPLE (1025 1575);
FORCENOTE
X
(1025 1475) 0;
DISPLAY LEFT (1025 1475);
DISPLAY 1.021277 (1025 1475);
PAINT PURPLE (1025 1475);
FORCENOTE
PIN C18
(925 1975) 0;
DISPLAY LEFT (925 1975);
DISPLAY 1.021277 (925 1975);
PAINT PURPLE (925 1975);
FORCENOTE
SINT_PRSNT
(825 1875) 0;
DISPLAY LEFT (825 1875);
DISPLAY 1.021277 (825 1875);
PAINT PURPLE (825 1875);
FORCENOTE
CGC_DUT_DETECT#
(125 1975) 0;
DISPLAY LEFT (125 1975);
DISPLAY 1.021277 (125 1975);
PAINT PURPLE (125 1975);
FORCENOTE
0
(400 1775) 0;
DISPLAY LEFT (400 1775);
DISPLAY 1.021277 (400 1775);
PAINT PURPLE (400 1775);
FORCENOTE
0
(400 1575) 0;
DISPLAY LEFT (400 1575);
DISPLAY 1.021277 (400 1575);
PAINT PURPLE (400 1575);
FORCENOTE
0
(400 1675) 0;
DISPLAY LEFT (400 1675);
DISPLAY 1.021277 (400 1675);
PAINT PURPLE (400 1675);
FORCENOTE
1
(400 1475) 0;
DISPLAY LEFT (400 1475);
DISPLAY 1.021277 (400 1475);
PAINT PURPLE (400 1475);
FORCENOTE
GPP_E
(-1225 4175) 0;
DISPLAY LEFT (-1225 4175);
DISPLAY 1.021277 (-1225 4175);
PAINT PURPLE (-1225 4175);
FORCENOTE
GPP_D
(-1250 4300) 0;
DISPLAY LEFT (-1250 4300);
DISPLAY 1.021277 (-1250 4300);
PAINT PURPLE (-1250 4300);
FORCENOTE
GPP_H
(-1250 2150) 0;
DISPLAY LEFT (-1250 2150);
DISPLAY 1.021277 (-1250 2150);
PAINT PURPLE (-1250 2150);
FORCENOTE
GPP_F
(-1300 3425) 0;
DISPLAY LEFT (-1300 3425);
DISPLAY 1.021277 (-1300 3425);
PAINT PURPLE (-1300 3425);
FORCENOTE
GPP_G
(-1300 2850) 0;
DISPLAY LEFT (-1300 2850);
DISPLAY 1.021277 (-1300 2850);
PAINT PURPLE (-1300 2850);
FORCENOTE
GPP_I
(-1275 1425) 0;
DISPLAY LEFT (-1275 1425);
DISPLAY 1.021277 (-1275 1425);
PAINT PURPLE (-1275 1425);
FORCENOTE
GPP_A
(-3325 3175) 0;
DISPLAY LEFT (-3325 3175);
DISPLAY 1.021277 (-3325 3175);
PAINT PURPLE (-3325 3175);
FORCENOTE
GPP_B
(-3325 3000) 0;
DISPLAY LEFT (-3325 3000);
DISPLAY 1.021277 (-3325 3000);
PAINT PURPLE (-3325 3000);
FORCENOTE
ROOM=SB_PU_PD
(-3650 550) 0;
DISPLAY LEFT (-3650 550);
DISPLAY 1.021277 (-3650 550);
PAINT PURPLE (-3650 550);
FORCENOTE
GPP_C
(-3375 2000) 0;
DISPLAY LEFT (-3375 2000);
DISPLAY 1.021277 (-3375 2000);
PAINT PURPLE (-3375 2000);
QUIT
